G04 ================== begin FILE IDENTIFICATION RECORD ==================*
G04 Layout Name:  16368-sb.brd*
G04 Film Name:    SE_REF_L3*
G04 File Format:  Gerber RS274X*
G04 File Origin:  Cadence Allegro 16.5-S056*
G04 Origin Date:  Tue Feb 07 09:07:45 2017*
G04 *
G04 Layer:  BOARD GEOMETRY/SE_REF_L3_TBL*
G04 Layer:  BOARD GEOMETRY/SE_REF_L3_L3*
G04 Layer:  BOARD GEOMETRY/PANEL_OUTLINE*
G04 *
G04 Offset:    (0.00 0.00)*
G04 Mirror:    No*
G04 Mode:      Positive*
G04 Rotation:  0*
G04 FullContactRelief:  No*
G04 UndefLineWidth:     6.00*
G04 ================== end FILE IDENTIFICATION RECORD ====================*
%FSLAX35Y35*MOIN*%
%IR0*IPPOS*OFA0.00000B0.00000*MIA0B0*SFA1.00000B1.00000*%
%ADD10C,.02*%
%ADD11C,.005*%
%ADD12C,.006*%
G75*
%LPD*%
G75*
G54D10*
G01X597544Y585326D02*
X1315044D01*
G01X597544Y654626D02*
Y585326D01*
G01Y654626D02*
X1315044D01*
G01X597544Y619976D02*
X1315044D01*
G01X772544Y654626D02*
Y585326D01*
G01X1000044Y654626D02*
Y585326D01*
G01X1105044Y654626D02*
Y585326D01*
G01X1315044Y654626D02*
Y585326D01*
G54D11*
G01X33800Y45000D02*
X28100Y39300D01*
G01X47000Y51000D02*
X32400D01*
G01D02*
X28100Y55300D01*
G01X39400Y46831D02*
X44607D01*
G01X52218Y47067D02*
Y45718D01*
G01D02*
X51500Y45000D01*
G01D02*
X33800D01*
G01X49730Y46821D02*
Y48270D01*
G01D02*
X47000Y51000D01*
G54D12*
G01X6250Y-52485D02*
Y-69985D01*
G01X1228Y-52485D02*
X11272D01*
G01X20038Y-69985D02*
Y-52485D01*
G01Y-60943D02*
X21130Y-59485D01*
X22222Y-58610D01*
X23968Y-58319D01*
X25278Y-58610D01*
X26807Y-59777D01*
X27462Y-61527D01*
Y-69985D01*
G01X41250Y-58319D02*
Y-69985D01*
G01Y-53652D02*
X40813Y-53360D01*
Y-52777D01*
X41250Y-52485D01*
X41687Y-52777D01*
Y-53360D01*
X41250Y-53652D01*
G01X55475Y-67944D02*
X56567Y-69110D01*
X58095Y-69985D01*
X59405D01*
X60715Y-69402D01*
X61588Y-68527D01*
X62025Y-67361D01*
X61807Y-65610D01*
X60933Y-64735D01*
X57003Y-62985D01*
X56130Y-60943D01*
X56567Y-59485D01*
X57440Y-58610D01*
X58750Y-58319D01*
X60060Y-58610D01*
X61370Y-59485D01*
G01X90693Y-74360D02*
X92222Y-75527D01*
X93968Y-75818D01*
X95496Y-75527D01*
X96807Y-74069D01*
X97680Y-72027D01*
Y-58319D01*
G01Y-60652D02*
X96807Y-59485D01*
X95496Y-58610D01*
X93968Y-58319D01*
X92222Y-58902D01*
X91130Y-60068D01*
X90256Y-62110D01*
X89820Y-64152D01*
X90038Y-65902D01*
X90912Y-67944D01*
X92222Y-69402D01*
X93968Y-69985D01*
X95278Y-69693D01*
X96807Y-68527D01*
X97680Y-67361D01*
G01X107975Y-62110D02*
X114962D01*
X114307Y-60068D01*
X113215Y-58902D01*
X111687Y-58319D01*
X110158Y-58610D01*
X108848Y-59485D01*
X107975Y-61527D01*
X107538Y-63277D01*
Y-65027D01*
X107975Y-66777D01*
X109067Y-68527D01*
X110377Y-69693D01*
X111905Y-69985D01*
X113433Y-69402D01*
X114962Y-67652D01*
G01X125693Y-69985D02*
Y-58319D01*
G01Y-60652D02*
X126785Y-59485D01*
X127877Y-58610D01*
X129405Y-58319D01*
X130496Y-58610D01*
X131807Y-59485D01*
G01X142320Y-69985D02*
Y-52485D01*
G01Y-61235D02*
X143412Y-59485D01*
X144722Y-58610D01*
X146032Y-58319D01*
X147996Y-58902D01*
X149307Y-60068D01*
X150180Y-62110D01*
Y-64443D01*
X149743Y-66777D01*
X148870Y-68527D01*
X147342Y-69693D01*
X146032Y-69985D01*
X144722Y-69693D01*
X143412Y-68819D01*
X142320Y-67361D01*
G01X160475Y-62110D02*
X167462D01*
X166807Y-60068D01*
X165715Y-58902D01*
X164187Y-58319D01*
X162658Y-58610D01*
X161348Y-59485D01*
X160475Y-61527D01*
X160038Y-63277D01*
Y-65027D01*
X160475Y-66777D01*
X161567Y-68527D01*
X162877Y-69693D01*
X164405Y-69985D01*
X165933Y-69402D01*
X167462Y-67652D01*
G01X178193Y-69985D02*
Y-58319D01*
G01Y-60652D02*
X179285Y-59485D01*
X180377Y-58610D01*
X181905Y-58319D01*
X182996Y-58610D01*
X184307Y-59485D01*
G01X216250Y-58319D02*
Y-69985D01*
G01Y-53652D02*
X215813Y-53360D01*
Y-52777D01*
X216250Y-52485D01*
X216687Y-52777D01*
Y-53360D01*
X216250Y-53652D01*
G01X230475Y-67944D02*
X231567Y-69110D01*
X233095Y-69985D01*
X234405D01*
X235715Y-69402D01*
X236588Y-68527D01*
X237025Y-67361D01*
X236807Y-65610D01*
X235933Y-64735D01*
X232003Y-62985D01*
X231130Y-60943D01*
X231567Y-59485D01*
X232440Y-58610D01*
X233750Y-58319D01*
X235060Y-58610D01*
X236370Y-59485D01*
G01X265256Y-74360D02*
X266785Y-75527D01*
X268095Y-75818D01*
X269842Y-75235D01*
X271152Y-73777D01*
X271807Y-71151D01*
Y-58319D01*
G01Y-53652D02*
X271370Y-53360D01*
Y-52777D01*
X271807Y-52485D01*
X272243Y-52777D01*
Y-53360D01*
X271807Y-53652D01*
G01X282538Y-58319D02*
Y-66485D01*
X283412Y-68527D01*
X284722Y-69693D01*
X286250Y-69985D01*
X287778Y-69693D01*
X289088Y-68527D01*
X289962Y-66485D01*
G01Y-69985D02*
Y-58319D01*
G01X300475Y-67944D02*
X301567Y-69110D01*
X303095Y-69985D01*
X304405D01*
X305715Y-69402D01*
X306588Y-68527D01*
X307025Y-67361D01*
X306807Y-65610D01*
X305933Y-64735D01*
X302003Y-62985D01*
X301130Y-60943D01*
X301567Y-59485D01*
X302440Y-58610D01*
X303750Y-58319D01*
X305060Y-58610D01*
X306370Y-59485D01*
G01X321250Y-52485D02*
Y-69985D01*
G01X318193Y-58319D02*
X324307D01*
G01X354940Y-69985D02*
Y-55110D01*
X355377Y-53652D01*
X356250Y-52777D01*
X357560Y-52485D01*
X358870Y-53068D01*
X359525Y-54527D01*
G01X356905Y-59485D02*
X352538D01*
G01X373750Y-69985D02*
X372440Y-69693D01*
X371130Y-68527D01*
X370256Y-66485D01*
X369820Y-64152D01*
X370256Y-61818D01*
X371130Y-59777D01*
X372440Y-58610D01*
X373750Y-58319D01*
X375060Y-58610D01*
X376370Y-59777D01*
X377243Y-61818D01*
X377462Y-64152D01*
X377243Y-66485D01*
X376370Y-68527D01*
X375060Y-69693D01*
X373750Y-69985D01*
G01X388193D02*
Y-58319D01*
G01Y-60652D02*
X389285Y-59485D01*
X390377Y-58610D01*
X391905Y-58319D01*
X392996Y-58610D01*
X394307Y-59485D01*
G01X421665Y-75235D02*
X422975Y-75818D01*
X424722Y-75235D01*
X425813Y-74069D01*
X426687Y-72610D01*
X427996Y-67944D01*
X430835Y-58319D01*
G01X423848D02*
X427996Y-67944D01*
G01X443750Y-69985D02*
X442440Y-69693D01*
X441130Y-68527D01*
X440256Y-66485D01*
X439820Y-64152D01*
X440256Y-61818D01*
X441130Y-59777D01*
X442440Y-58610D01*
X443750Y-58319D01*
X445060Y-58610D01*
X446370Y-59777D01*
X447243Y-61818D01*
X447462Y-64152D01*
X447243Y-66485D01*
X446370Y-68527D01*
X445060Y-69693D01*
X443750Y-69985D01*
G01X457538Y-58319D02*
Y-66485D01*
X458412Y-68527D01*
X459722Y-69693D01*
X461250Y-69985D01*
X462778Y-69693D01*
X464088Y-68527D01*
X464962Y-66485D01*
G01Y-69985D02*
Y-58319D01*
G01X475693Y-69985D02*
Y-58319D01*
G01Y-60652D02*
X476785Y-59485D01*
X477877Y-58610D01*
X479405Y-58319D01*
X480496Y-58610D01*
X481807Y-59485D01*
G01X510693Y-69985D02*
Y-58319D01*
G01Y-60652D02*
X511785Y-59485D01*
X512877Y-58610D01*
X514405Y-58319D01*
X515496Y-58610D01*
X516807Y-59485D01*
G01X527975Y-62110D02*
X534962D01*
X534307Y-60068D01*
X533215Y-58902D01*
X531687Y-58319D01*
X530158Y-58610D01*
X528848Y-59485D01*
X527975Y-61527D01*
X527538Y-63277D01*
Y-65027D01*
X527975Y-66777D01*
X529067Y-68527D01*
X530377Y-69693D01*
X531905Y-69985D01*
X533433Y-69402D01*
X534962Y-67652D01*
G01X547440Y-69985D02*
Y-55110D01*
X547877Y-53652D01*
X548750Y-52777D01*
X550060Y-52485D01*
X551370Y-53068D01*
X552025Y-54527D01*
G01X549405Y-59485D02*
X545038D01*
G01X562975Y-62110D02*
X569962D01*
X569307Y-60068D01*
X568215Y-58902D01*
X566687Y-58319D01*
X565158Y-58610D01*
X563848Y-59485D01*
X562975Y-61527D01*
X562538Y-63277D01*
Y-65027D01*
X562975Y-66777D01*
X564067Y-68527D01*
X565377Y-69693D01*
X566905Y-69985D01*
X568433Y-69402D01*
X569962Y-67652D01*
G01X580693Y-69985D02*
Y-58319D01*
G01Y-60652D02*
X581785Y-59485D01*
X582877Y-58610D01*
X584405Y-58319D01*
X585496Y-58610D01*
X586807Y-59485D01*
G01X597975Y-62110D02*
X604962D01*
X604307Y-60068D01*
X603215Y-58902D01*
X601687Y-58319D01*
X600158Y-58610D01*
X598848Y-59485D01*
X597975Y-61527D01*
X597538Y-63277D01*
Y-65027D01*
X597975Y-66777D01*
X599067Y-68527D01*
X600377Y-69693D01*
X601905Y-69985D01*
X603433Y-69402D01*
X604962Y-67652D01*
G01X615038Y-69985D02*
Y-58319D01*
G01Y-61235D02*
X615912Y-59777D01*
X617222Y-58610D01*
X618968Y-58319D01*
X620496Y-58610D01*
X621807Y-59777D01*
X622462Y-61818D01*
Y-69985D01*
G01X639743Y-59777D02*
X638215Y-58610D01*
X636905Y-58319D01*
X635158Y-58902D01*
X633848Y-60068D01*
X632975Y-62110D01*
X632756Y-64152D01*
X632975Y-66194D01*
X633848Y-67944D01*
X635158Y-69402D01*
X636905Y-69985D01*
X638433Y-69402D01*
X639743Y-68235D01*
G01X650475Y-62110D02*
X657462D01*
X656807Y-60068D01*
X655715Y-58902D01*
X654187Y-58319D01*
X652658Y-58610D01*
X651348Y-59485D01*
X650475Y-61527D01*
X650038Y-63277D01*
Y-65027D01*
X650475Y-66777D01*
X651567Y-68527D01*
X652877Y-69693D01*
X654405Y-69985D01*
X655933Y-69402D01*
X657462Y-67652D01*
G01X688750Y-52485D02*
Y-69985D01*
G01X685693Y-58319D02*
X691807D01*
G01X706250Y-69985D02*
X704940Y-69693D01*
X703630Y-68527D01*
X702756Y-66485D01*
X702320Y-64152D01*
X702756Y-61818D01*
X703630Y-59777D01*
X704940Y-58610D01*
X706250Y-58319D01*
X707560Y-58610D01*
X708870Y-59777D01*
X709743Y-61818D01*
X709962Y-64152D01*
X709743Y-66485D01*
X708870Y-68527D01*
X707560Y-69693D01*
X706250Y-69985D01*
G01X739940D02*
Y-55110D01*
X740377Y-53652D01*
X741250Y-52777D01*
X742560Y-52485D01*
X743870Y-53068D01*
X744525Y-54527D01*
G01X741905Y-59485D02*
X737538D01*
G01X758750Y-58319D02*
Y-69985D01*
G01Y-53652D02*
X758313Y-53360D01*
Y-52777D01*
X758750Y-52485D01*
X759187Y-52777D01*
Y-53360D01*
X758750Y-53652D01*
G01X772538Y-69985D02*
Y-58319D01*
G01Y-61235D02*
X773412Y-59777D01*
X774722Y-58610D01*
X776468Y-58319D01*
X777996Y-58610D01*
X779307Y-59777D01*
X779962Y-61818D01*
Y-69985D01*
G01X797680Y-52485D02*
Y-69985D01*
G01Y-67361D02*
X796807Y-68819D01*
X795496Y-69693D01*
X793968Y-69985D01*
X792222Y-69402D01*
X790912Y-67944D01*
X790038Y-66194D01*
X789820Y-64152D01*
X790038Y-62110D01*
X790912Y-60360D01*
X792222Y-58902D01*
X793968Y-58319D01*
X795496Y-58610D01*
X796588Y-59194D01*
X797680Y-60360D01*
G01X828750Y-52485D02*
Y-69985D01*
G01X825693Y-58319D02*
X831807D01*
G01X842538Y-69985D02*
Y-52485D01*
G01Y-60943D02*
X843630Y-59485D01*
X844722Y-58610D01*
X846468Y-58319D01*
X847778Y-58610D01*
X849307Y-59777D01*
X849962Y-61527D01*
Y-69985D01*
G01X860475Y-62110D02*
X867462D01*
X866807Y-60068D01*
X865715Y-58902D01*
X864187Y-58319D01*
X862658Y-58610D01*
X861348Y-59485D01*
X860475Y-61527D01*
X860038Y-63277D01*
Y-65027D01*
X860475Y-66777D01*
X861567Y-68527D01*
X862877Y-69693D01*
X864405Y-69985D01*
X865933Y-69402D01*
X867462Y-67652D01*
G01X894165D02*
X895912Y-69110D01*
X897877Y-69985D01*
X899623D01*
X901370Y-69110D01*
X902680Y-67652D01*
X903335Y-65610D01*
X902898Y-63569D01*
X901807Y-61818D01*
X899842Y-60652D01*
X897222Y-60068D01*
X895693Y-58902D01*
X895038Y-56860D01*
X895475Y-54818D01*
X896567Y-53360D01*
X898095Y-52485D01*
X899623D01*
X901152Y-53068D01*
X902462Y-54527D01*
G01X920617Y-69985D02*
X911883D01*
Y-52485D01*
X920617D01*
G01X917123Y-60943D02*
X911883D01*
G01X951250Y-58319D02*
Y-69985D01*
G01Y-53652D02*
X950813Y-53360D01*
Y-52777D01*
X951250Y-52485D01*
X951687Y-52777D01*
Y-53360D01*
X951250Y-53652D01*
G01X962200Y-69985D02*
Y-58319D01*
G01Y-61527D02*
X962855Y-60068D01*
X963947Y-58902D01*
X965475Y-58319D01*
X967003Y-58902D01*
X968095Y-60068D01*
X968750Y-61527D01*
Y-69985D01*
G01Y-61527D02*
X969405Y-60068D01*
X970496Y-58902D01*
X972025Y-58319D01*
X973553Y-58902D01*
X974645Y-60068D01*
X975300Y-61818D01*
Y-69985D01*
G01X982320Y-75818D02*
Y-58319D01*
G01Y-60943D02*
X983412Y-59485D01*
X984503Y-58610D01*
X986250Y-58319D01*
X987778Y-58610D01*
X989307Y-60068D01*
X989962Y-62110D01*
X990180Y-64152D01*
X989962Y-66194D01*
X989307Y-68235D01*
X987996Y-69402D01*
X986250Y-69985D01*
X984722Y-69693D01*
X983193Y-68819D01*
X982320Y-67652D01*
G01X1000475Y-62110D02*
X1007462D01*
X1006807Y-60068D01*
X1005715Y-58902D01*
X1004187Y-58319D01*
X1002658Y-58610D01*
X1001348Y-59485D01*
X1000475Y-61527D01*
X1000038Y-63277D01*
Y-65027D01*
X1000475Y-66777D01*
X1001567Y-68527D01*
X1002877Y-69693D01*
X1004405Y-69985D01*
X1005933Y-69402D01*
X1007462Y-67652D01*
G01X1025180Y-52485D02*
Y-69985D01*
G01Y-67361D02*
X1024307Y-68819D01*
X1022996Y-69693D01*
X1021468Y-69985D01*
X1019722Y-69402D01*
X1018412Y-67944D01*
X1017538Y-66194D01*
X1017320Y-64152D01*
X1017538Y-62110D01*
X1018412Y-60360D01*
X1019722Y-58902D01*
X1021468Y-58319D01*
X1022996Y-58610D01*
X1024088Y-59194D01*
X1025180Y-60360D01*
G01X1042680Y-69985D02*
Y-58319D01*
G01Y-60360D02*
X1041807Y-59194D01*
X1040496Y-58610D01*
X1038968Y-58319D01*
X1037440Y-58902D01*
X1036130Y-60068D01*
X1035256Y-61818D01*
X1034820Y-64152D01*
X1035256Y-66485D01*
X1036130Y-68235D01*
X1037440Y-69402D01*
X1038968Y-69985D01*
X1040496Y-69693D01*
X1041807Y-68819D01*
X1042680Y-67652D01*
G01X1052538Y-69985D02*
Y-58319D01*
G01Y-61235D02*
X1053412Y-59777D01*
X1054722Y-58610D01*
X1056468Y-58319D01*
X1057996Y-58610D01*
X1059307Y-59777D01*
X1059962Y-61818D01*
Y-69985D01*
G01X1077243Y-59777D02*
X1075715Y-58610D01*
X1074405Y-58319D01*
X1072658Y-58902D01*
X1071348Y-60068D01*
X1070475Y-62110D01*
X1070256Y-64152D01*
X1070475Y-66194D01*
X1071348Y-67944D01*
X1072658Y-69402D01*
X1074405Y-69985D01*
X1075933Y-69402D01*
X1077243Y-68235D01*
G01X1087975Y-62110D02*
X1094962D01*
X1094307Y-60068D01*
X1093215Y-58902D01*
X1091687Y-58319D01*
X1090158Y-58610D01*
X1088848Y-59485D01*
X1087975Y-61527D01*
X1087538Y-63277D01*
Y-65027D01*
X1087975Y-66777D01*
X1089067Y-68527D01*
X1090377Y-69693D01*
X1091905Y-69985D01*
X1093433Y-69402D01*
X1094962Y-67652D01*
G01X1126250Y-52485D02*
Y-69985D01*
G01X1123193Y-58319D02*
X1129307D01*
G01X1140693Y-69985D02*
Y-58319D01*
G01Y-60652D02*
X1141785Y-59485D01*
X1142877Y-58610D01*
X1144405Y-58319D01*
X1145496Y-58610D01*
X1146807Y-59485D01*
G01X1165180Y-69985D02*
Y-58319D01*
G01Y-60360D02*
X1164307Y-59194D01*
X1162996Y-58610D01*
X1161468Y-58319D01*
X1159940Y-58902D01*
X1158630Y-60068D01*
X1157756Y-61818D01*
X1157320Y-64152D01*
X1157756Y-66485D01*
X1158630Y-68235D01*
X1159940Y-69402D01*
X1161468Y-69985D01*
X1162996Y-69693D01*
X1164307Y-68819D01*
X1165180Y-67652D01*
G01X1182243Y-59777D02*
X1180715Y-58610D01*
X1179405Y-58319D01*
X1177658Y-58902D01*
X1176348Y-60068D01*
X1175475Y-62110D01*
X1175256Y-64152D01*
X1175475Y-66194D01*
X1176348Y-67944D01*
X1177658Y-69402D01*
X1179405Y-69985D01*
X1180933Y-69402D01*
X1182243Y-68235D01*
G01X1192975Y-62110D02*
X1199962D01*
X1199307Y-60068D01*
X1198215Y-58902D01*
X1196687Y-58319D01*
X1195158Y-58610D01*
X1193848Y-59485D01*
X1192975Y-61527D01*
X1192538Y-63277D01*
Y-65027D01*
X1192975Y-66777D01*
X1194067Y-68527D01*
X1195377Y-69693D01*
X1196905Y-69985D01*
X1198433Y-69402D01*
X1199962Y-67652D01*
G01X1210475Y-67944D02*
X1211567Y-69110D01*
X1213095Y-69985D01*
X1214405D01*
X1215715Y-69402D01*
X1216588Y-68527D01*
X1217025Y-67361D01*
X1216807Y-65610D01*
X1215933Y-64735D01*
X1212003Y-62985D01*
X1211130Y-60943D01*
X1211567Y-59485D01*
X1212440Y-58610D01*
X1213750Y-58319D01*
X1215060Y-58610D01*
X1216370Y-59485D01*
G01X1248750Y-58319D02*
Y-69985D01*
G01Y-53652D02*
X1248313Y-53360D01*
Y-52777D01*
X1248750Y-52485D01*
X1249187Y-52777D01*
Y-53360D01*
X1248750Y-53652D01*
G01X1262538Y-69985D02*
Y-58319D01*
G01Y-61235D02*
X1263412Y-59777D01*
X1264722Y-58610D01*
X1266468Y-58319D01*
X1267996Y-58610D01*
X1269307Y-59777D01*
X1269962Y-61818D01*
Y-69985D01*
G01X1301250D02*
Y-52485D01*
G01X1322680Y-69985D02*
Y-58319D01*
G01Y-60360D02*
X1321807Y-59194D01*
X1320496Y-58610D01*
X1318968Y-58319D01*
X1317440Y-58902D01*
X1316130Y-60068D01*
X1315256Y-61818D01*
X1314820Y-64152D01*
X1315256Y-66485D01*
X1316130Y-68235D01*
X1317440Y-69402D01*
X1318968Y-69985D01*
X1320496Y-69693D01*
X1321807Y-68819D01*
X1322680Y-67652D01*
G01X1331665Y-75235D02*
X1332975Y-75818D01*
X1334722Y-75235D01*
X1335813Y-74069D01*
X1336687Y-72610D01*
X1337996Y-67944D01*
X1340835Y-58319D01*
G01X1333848D02*
X1337996Y-67944D01*
G01X1350475Y-62110D02*
X1357462D01*
X1356807Y-60068D01*
X1355715Y-58902D01*
X1354187Y-58319D01*
X1352658Y-58610D01*
X1351348Y-59485D01*
X1350475Y-61527D01*
X1350038Y-63277D01*
Y-65027D01*
X1350475Y-66777D01*
X1351567Y-68527D01*
X1352877Y-69693D01*
X1354405Y-69985D01*
X1355933Y-69402D01*
X1357462Y-67652D01*
G01X1368193Y-69985D02*
Y-58319D01*
G01Y-60652D02*
X1369285Y-59485D01*
X1370377Y-58610D01*
X1371905Y-58319D01*
X1372996Y-58610D01*
X1374307Y-59485D01*
G01X1401883Y-52485D02*
Y-69985D01*
X1410617D01*
G01X1418947Y-66485D02*
X1420256Y-68527D01*
X1422003Y-69693D01*
X1423968Y-69985D01*
X1425715Y-69693D01*
X1427462Y-68235D01*
X1428553Y-66485D01*
X1428772Y-64735D01*
X1428335Y-62694D01*
X1426807Y-61235D01*
X1425278Y-60652D01*
X1423313D01*
G01X1425278D02*
X1426588Y-59777D01*
X1427680Y-58319D01*
X1428117Y-56569D01*
X1427680Y-54818D01*
X1426588Y-53360D01*
X1424623Y-52485D01*
X1422658Y-52777D01*
X1420693Y-53944D01*
G01X1441250Y-70568D02*
X1440813Y-70277D01*
Y-69693D01*
X1441250Y-69402D01*
X1441687Y-69693D01*
Y-70277D01*
X1441250Y-70568D01*
G01X599509Y666709D02*
X601256Y665251D01*
X603221Y664376D01*
X604967D01*
X606714Y665251D01*
X608024Y666709D01*
X608679Y668751D01*
X608242Y670792D01*
X607151Y672543D01*
X605186Y673709D01*
X602566Y674293D01*
X601037Y675459D01*
X600382Y677501D01*
X600819Y679543D01*
X601911Y681001D01*
X603439Y681876D01*
X604967D01*
X606496Y681293D01*
X607806Y679834D01*
G01X625961Y664376D02*
X617227D01*
Y681876D01*
X625961D01*
G01X622467Y673418D02*
X617227D01*
G01X653974Y681876D02*
X659214D01*
G01X656594D02*
Y664376D01*
G01X653974D02*
X659214D01*
G01X668417D02*
Y681876D01*
X674094Y667293D01*
X679771Y681876D01*
Y664376D01*
G01X687227D02*
Y681876D01*
X692467D01*
X694214Y681001D01*
X695524Y678959D01*
X695961Y676626D01*
X695524Y674293D01*
X694432Y672543D01*
X692467Y671667D01*
X687227D01*
G01X713461Y664376D02*
X704727D01*
Y681876D01*
X713461D01*
G01X709967Y673418D02*
X704727D01*
G01X721791Y664376D02*
Y681876D01*
X726157D01*
X727904Y681001D01*
X729214Y679834D01*
X730306Y678085D01*
X731179Y676042D01*
X731397Y673126D01*
X731179Y670209D01*
X730306Y668167D01*
X729214Y666417D01*
X727904Y665251D01*
X726157Y664376D01*
X721791D01*
G01X738635D02*
X744094Y681876D01*
X749553Y664376D01*
G01X747587Y670501D02*
X740600D01*
G01X756572Y664376D02*
Y681876D01*
X766616Y664376D01*
Y681876D01*
G01X783897Y680417D02*
X782587Y681293D01*
X781059Y681876D01*
X779312D01*
X777347Y681001D01*
X775819Y679543D01*
X774727Y677792D01*
X773854Y674876D01*
X773635Y672251D01*
X774072Y669626D01*
X774727Y667876D01*
X776037Y666126D01*
X777566Y664959D01*
X779094Y664376D01*
X780622D01*
X782151Y664959D01*
X783461Y665834D01*
X784553Y667000D01*
G01X800961Y664376D02*
X792227D01*
Y681876D01*
X800961D01*
G01X797467Y673418D02*
X792227D01*
G01X831594Y681876D02*
Y664376D01*
G01X826572Y681876D02*
X836616D01*
G01X843635Y664376D02*
X849094Y681876D01*
X854553Y664376D01*
G01X852587Y670501D02*
X845600D01*
G01X868340Y673709D02*
X869214Y674584D01*
X869869Y676042D01*
X870306Y678085D01*
X869869Y679834D01*
X868996Y681001D01*
X867467Y681876D01*
X861572D01*
Y664376D01*
X868777D01*
X870306Y665542D01*
X871179Y667293D01*
X871616Y669334D01*
X871179Y671376D01*
X869869Y673126D01*
X868340Y673709D01*
X861572D01*
G01X879727Y681876D02*
Y664376D01*
X888461D01*
G01X905961D02*
X897227D01*
Y681876D01*
X905961D01*
G01X902467Y673418D02*
X897227D01*
G01X919094Y663793D02*
X918657Y664084D01*
Y664668D01*
X919094Y664959D01*
X919531Y664668D01*
Y664084D01*
X919094Y663793D01*
G01Y671667D02*
X918657Y671959D01*
Y672543D01*
X919094Y672834D01*
X919531Y672543D01*
Y671959D01*
X919094Y671667D01*
G01X949727Y681876D02*
Y664376D01*
X958461D01*
G01X966791Y667876D02*
X968100Y665834D01*
X969847Y664668D01*
X971812Y664376D01*
X973559Y664668D01*
X975306Y666126D01*
X976397Y667876D01*
X976616Y669626D01*
X976179Y671667D01*
X974651Y673126D01*
X973122Y673709D01*
X971157D01*
G01X973122D02*
X974432Y674584D01*
X975524Y676042D01*
X975961Y677792D01*
X975524Y679543D01*
X974432Y681001D01*
X972467Y681876D01*
X970502Y681584D01*
X968537Y680417D01*
G01X653991Y597700D02*
X655300Y596242D01*
X656829Y595368D01*
X658794Y595076D01*
X660759Y595659D01*
X662287Y596826D01*
X663379Y598867D01*
X663597Y601201D01*
X663161Y603534D01*
X662069Y604993D01*
X660540Y606159D01*
X659012Y606451D01*
X657484Y606159D01*
X655519Y604993D01*
X656174Y612576D01*
X662069D01*
G01X676294D02*
X674547Y611993D01*
X673237Y610534D01*
X672364Y608785D01*
X671709Y606451D01*
X671491Y603826D01*
X671709Y601201D01*
X672364Y598867D01*
X673237Y597117D01*
X674547Y595659D01*
X676294Y595076D01*
X678040Y595659D01*
X679351Y597117D01*
X680224Y598867D01*
X680879Y601201D01*
X681097Y603826D01*
X680879Y606451D01*
X680224Y608785D01*
X679351Y610534D01*
X678040Y611993D01*
X676294Y612576D01*
G01X693794Y594493D02*
X693357Y594784D01*
Y595368D01*
X693794Y595659D01*
X694231Y595368D01*
Y594784D01*
X693794Y594493D01*
G01X711294Y612576D02*
X709547Y611993D01*
X708237Y610534D01*
X707364Y608785D01*
X706709Y606451D01*
X706491Y603826D01*
X706709Y601201D01*
X707364Y598867D01*
X708237Y597117D01*
X709547Y595659D01*
X711294Y595076D01*
X713040Y595659D01*
X714351Y597117D01*
X715224Y598867D01*
X715879Y601201D01*
X716097Y603826D01*
X715879Y606451D01*
X715224Y608785D01*
X714351Y610534D01*
X713040Y611993D01*
X711294Y612576D01*
G01X621174Y647226D02*
X626414D01*
G01X623794D02*
Y629726D01*
G01X621174D02*
X626414D01*
G01X635617D02*
Y647226D01*
X641294Y632643D01*
X646971Y647226D01*
Y629726D01*
G01X654427D02*
Y647226D01*
X659667D01*
X661414Y646351D01*
X662724Y644309D01*
X663161Y641976D01*
X662724Y639643D01*
X661632Y637893D01*
X659667Y637017D01*
X654427D01*
G01X675202Y623893D02*
X673019Y626809D01*
X671927Y629726D01*
Y641392D01*
X673019Y644309D01*
X675202Y647226D01*
G01X693794Y629726D02*
X692047Y630018D01*
X690519Y631184D01*
X689209Y632934D01*
X688335Y634976D01*
X687899Y637309D01*
Y639643D01*
X688335Y641976D01*
X689209Y644018D01*
X690519Y645767D01*
X692047Y646934D01*
X693794Y647226D01*
X695540Y646934D01*
X697069Y645767D01*
X698379Y644018D01*
X699253Y641976D01*
X699689Y639643D01*
Y637309D01*
X699253Y634976D01*
X698379Y632934D01*
X697069Y631184D01*
X695540Y630018D01*
X693794Y629726D01*
G01X707582D02*
Y647226D01*
G01Y638768D02*
X708674Y640226D01*
X709766Y641101D01*
X711512Y641392D01*
X712822Y641101D01*
X714351Y639934D01*
X715006Y638184D01*
Y629726D01*
G01X722244D02*
Y641392D01*
G01Y638184D02*
X722899Y639643D01*
X723991Y640809D01*
X725519Y641392D01*
X727047Y640809D01*
X728139Y639643D01*
X728794Y638184D01*
Y629726D01*
G01Y638184D02*
X729449Y639643D01*
X730540Y640809D01*
X732069Y641392D01*
X733597Y640809D01*
X734689Y639643D01*
X735344Y637893D01*
Y629726D01*
G01X747386Y623893D02*
X749569Y626809D01*
X750661Y629726D01*
Y641392D01*
X749569Y644309D01*
X747386Y647226D01*
G01X792244D02*
X795300Y629726D01*
X798794Y647226D01*
X802287Y629726D01*
X805344Y647226D01*
G01X813674D02*
X818914D01*
G01X816294D02*
Y629726D01*
G01X813674D02*
X818914D01*
G01X828991D02*
Y647226D01*
X833357D01*
X835104Y646351D01*
X836414Y645184D01*
X837506Y643435D01*
X838379Y641392D01*
X838597Y638476D01*
X838379Y635559D01*
X837506Y633517D01*
X836414Y631767D01*
X835104Y630601D01*
X833357Y629726D01*
X828991D01*
G01X851294Y647226D02*
Y629726D01*
G01X846272Y647226D02*
X856316D01*
G01X864209Y629726D02*
Y647226D01*
G01X873379D02*
Y629726D01*
G01Y638476D02*
X864209D01*
G01X885202Y623893D02*
X883019Y626809D01*
X881927Y629726D01*
Y641392D01*
X883019Y644309D01*
X885202Y647226D01*
G01X897244Y629726D02*
Y641392D01*
G01Y638184D02*
X897899Y639643D01*
X898991Y640809D01*
X900519Y641392D01*
X902047Y640809D01*
X903139Y639643D01*
X903794Y638184D01*
Y629726D01*
G01Y638184D02*
X904449Y639643D01*
X905540Y640809D01*
X907069Y641392D01*
X908597Y640809D01*
X909689Y639643D01*
X910344Y637893D01*
Y629726D01*
G01X921294Y641392D02*
Y629726D01*
G01Y646059D02*
X920857Y646351D01*
Y646934D01*
X921294Y647226D01*
X921731Y646934D01*
Y646351D01*
X921294Y646059D01*
G01X938794Y629726D02*
Y647226D01*
G01X953019Y631767D02*
X954111Y630601D01*
X955639Y629726D01*
X956949D01*
X958259Y630309D01*
X959132Y631184D01*
X959569Y632350D01*
X959351Y634101D01*
X958477Y634976D01*
X954547Y636726D01*
X953674Y638768D01*
X954111Y640226D01*
X954984Y641101D01*
X956294Y641392D01*
X957604Y641101D01*
X958914Y640226D01*
G01X974886Y623893D02*
X977069Y626809D01*
X978161Y629726D01*
Y641392D01*
X977069Y644309D01*
X974886Y647226D01*
G01X863991Y597700D02*
X865300Y596242D01*
X866829Y595368D01*
X868794Y595076D01*
X870759Y595659D01*
X872287Y596826D01*
X873379Y598867D01*
X873597Y601201D01*
X873161Y603534D01*
X872069Y604993D01*
X870540Y606159D01*
X869012Y606451D01*
X867484Y606159D01*
X865519Y604993D01*
X866174Y612576D01*
X872069D01*
G01X886294Y594493D02*
X885857Y594784D01*
Y595368D01*
X886294Y595659D01*
X886731Y595368D01*
Y594784D01*
X886294Y594493D01*
G01X903794Y612576D02*
X902047Y611993D01*
X900737Y610534D01*
X899864Y608785D01*
X899209Y606451D01*
X898991Y603826D01*
X899209Y601201D01*
X899864Y598867D01*
X900737Y597117D01*
X902047Y595659D01*
X903794Y595076D01*
X905540Y595659D01*
X906851Y597117D01*
X907724Y598867D01*
X908379Y601201D01*
X908597Y603826D01*
X908379Y606451D01*
X907724Y608785D01*
X906851Y610534D01*
X905540Y611993D01*
X903794Y612576D01*
G01X1026294Y647226D02*
Y629726D01*
G01X1021272Y647226D02*
X1031316D01*
G01X1043794Y629726D02*
Y637601D01*
X1039427Y647226D01*
G01X1048161D02*
X1043794Y637601D01*
G01X1056927Y629726D02*
Y647226D01*
X1062167D01*
X1063914Y646351D01*
X1065224Y644309D01*
X1065661Y641976D01*
X1065224Y639643D01*
X1064132Y637893D01*
X1062167Y637017D01*
X1056927D01*
G01X1083161Y629726D02*
X1074427D01*
Y647226D01*
X1083161D01*
G01X1079667Y638768D02*
X1074427D01*
G01X1039209Y597409D02*
X1040956Y595951D01*
X1042921Y595076D01*
X1044667D01*
X1046414Y595951D01*
X1047724Y597409D01*
X1048379Y599451D01*
X1047942Y601492D01*
X1046851Y603243D01*
X1044886Y604409D01*
X1042266Y604993D01*
X1040737Y606159D01*
X1040082Y608201D01*
X1040519Y610243D01*
X1041611Y611701D01*
X1043139Y612576D01*
X1044667D01*
X1046196Y611993D01*
X1047506Y610534D01*
G01X1065661Y595076D02*
X1056927D01*
Y612576D01*
X1065661D01*
G01X1062167Y604118D02*
X1056927D01*
G01X1170677Y612576D02*
Y595076D01*
X1179411D01*
G01X1188396Y609659D02*
X1189706Y611409D01*
X1191234Y612284D01*
X1192981Y612576D01*
X1195164Y611993D01*
X1196692Y610534D01*
X1197129Y608785D01*
X1196911Y607034D01*
X1196037Y605576D01*
X1191671Y602659D01*
X1189706Y600618D01*
X1188396Y597700D01*
X1187959Y595076D01*
X1197129D01*
G01X1206114Y594493D02*
X1213974Y612576D01*
G01X1223177D02*
Y595076D01*
X1231911D01*
G01X1240241Y597700D02*
X1241550Y596242D01*
X1243079Y595368D01*
X1245044Y595076D01*
X1247009Y595659D01*
X1248537Y596826D01*
X1249629Y598867D01*
X1249847Y601201D01*
X1249411Y603534D01*
X1248319Y604993D01*
X1246790Y606159D01*
X1245262Y606451D01*
X1243734Y606159D01*
X1241769Y604993D01*
X1242424Y612576D01*
X1248319D01*
G01X1126927Y629726D02*
Y647226D01*
X1132386D01*
X1134132Y646351D01*
X1135224Y645184D01*
X1135661Y642851D01*
X1135224Y640517D01*
X1133914Y639059D01*
X1132386Y638184D01*
X1126927D01*
G01X1132386D02*
X1135661Y629726D01*
G01X1145519Y637601D02*
X1152506D01*
X1151851Y639643D01*
X1150759Y640809D01*
X1149231Y641392D01*
X1147702Y641101D01*
X1146392Y640226D01*
X1145519Y638184D01*
X1145082Y636434D01*
Y634684D01*
X1145519Y632934D01*
X1146611Y631184D01*
X1147921Y630018D01*
X1149449Y629726D01*
X1150977Y630309D01*
X1152506Y632059D01*
G01X1164984Y629726D02*
Y644601D01*
X1165421Y646059D01*
X1166294Y646934D01*
X1167604Y647226D01*
X1168914Y646643D01*
X1169569Y645184D01*
G01X1166949Y640226D02*
X1162582D01*
G01X1183794Y629143D02*
X1183357Y629434D01*
Y630018D01*
X1183794Y630309D01*
X1184231Y630018D01*
Y629434D01*
X1183794Y629143D01*
G01X1214427Y629726D02*
Y647226D01*
X1219667D01*
X1221414Y646351D01*
X1222724Y644309D01*
X1223161Y641976D01*
X1222724Y639643D01*
X1221632Y637893D01*
X1219667Y637017D01*
X1214427D01*
G01X1236294Y629726D02*
Y647226D01*
G01X1257724Y629726D02*
Y641392D01*
G01Y639351D02*
X1256851Y640517D01*
X1255540Y641101D01*
X1254012Y641392D01*
X1252484Y640809D01*
X1251174Y639643D01*
X1250300Y637893D01*
X1249864Y635559D01*
X1250300Y633226D01*
X1251174Y631476D01*
X1252484Y630309D01*
X1254012Y629726D01*
X1255540Y630018D01*
X1256851Y630892D01*
X1257724Y632059D01*
G01X1267582Y629726D02*
Y641392D01*
G01Y638476D02*
X1268456Y639934D01*
X1269766Y641101D01*
X1271512Y641392D01*
X1273040Y641101D01*
X1274351Y639934D01*
X1275006Y637893D01*
Y629726D01*
G01X1285519Y637601D02*
X1292506D01*
X1291851Y639643D01*
X1290759Y640809D01*
X1289231Y641392D01*
X1287702Y641101D01*
X1286392Y640226D01*
X1285519Y638184D01*
X1285082Y636434D01*
Y634684D01*
X1285519Y632934D01*
X1286611Y631184D01*
X1287921Y630018D01*
X1289449Y629726D01*
X1290977Y630309D01*
X1292506Y632059D01*
G01X1406594Y606742D02*
Y595076D01*
G01Y611409D02*
X1406157Y611701D01*
Y612284D01*
X1406594Y612576D01*
X1407031Y612284D01*
Y611701D01*
X1406594Y611409D01*
G01X1420819Y597117D02*
X1421911Y595951D01*
X1423439Y595076D01*
X1424749D01*
X1426059Y595659D01*
X1426932Y596534D01*
X1427369Y597700D01*
X1427151Y599451D01*
X1426277Y600326D01*
X1422347Y602076D01*
X1421474Y604118D01*
X1421911Y605576D01*
X1422784Y606451D01*
X1424094Y606742D01*
X1425404Y606451D01*
X1426714Y605576D01*
G01X1454072Y595076D02*
Y612576D01*
X1464116Y595076D01*
Y612576D01*
G01X1476594Y595076D02*
X1474847Y595368D01*
X1473319Y596534D01*
X1472009Y598284D01*
X1471135Y600326D01*
X1470699Y602659D01*
Y604993D01*
X1471135Y607326D01*
X1472009Y609368D01*
X1473319Y611117D01*
X1474847Y612284D01*
X1476594Y612576D01*
X1478340Y612284D01*
X1479869Y611117D01*
X1481179Y609368D01*
X1482053Y607326D01*
X1482489Y604993D01*
Y602659D01*
X1482053Y600326D01*
X1481179Y598284D01*
X1479869Y596534D01*
X1478340Y595368D01*
X1476594Y595076D01*
G01X1494094Y612576D02*
Y595076D01*
G01X1489072Y612576D02*
X1499116D01*
G01X1525382Y606742D02*
Y598576D01*
X1526256Y596534D01*
X1527566Y595368D01*
X1529094Y595076D01*
X1530622Y595368D01*
X1531932Y596534D01*
X1532806Y598576D01*
G01Y595076D02*
Y606742D01*
G01X1543319Y597117D02*
X1544411Y595951D01*
X1545939Y595076D01*
X1547249D01*
X1548559Y595659D01*
X1549432Y596534D01*
X1549869Y597700D01*
X1549651Y599451D01*
X1548777Y600326D01*
X1544847Y602076D01*
X1543974Y604118D01*
X1544411Y605576D01*
X1545284Y606451D01*
X1546594Y606742D01*
X1547904Y606451D01*
X1549214Y605576D01*
G01X1560819Y602951D02*
X1567806D01*
X1567151Y604993D01*
X1566059Y606159D01*
X1564531Y606742D01*
X1563002Y606451D01*
X1561692Y605576D01*
X1560819Y603534D01*
X1560382Y601784D01*
Y600034D01*
X1560819Y598284D01*
X1561911Y596534D01*
X1563221Y595368D01*
X1564749Y595076D01*
X1566277Y595659D01*
X1567806Y597409D01*
G01X1585524Y612576D02*
Y595076D01*
G01Y597700D02*
X1584651Y596242D01*
X1583340Y595368D01*
X1581812Y595076D01*
X1580066Y595659D01*
X1578756Y597117D01*
X1577882Y598867D01*
X1577664Y600909D01*
X1577882Y602951D01*
X1578756Y604701D01*
X1580066Y606159D01*
X1581812Y606742D01*
X1583340Y606451D01*
X1584432Y605867D01*
X1585524Y604701D01*
G01X1616594Y606742D02*
Y595076D01*
G01Y611409D02*
X1616157Y611701D01*
Y612284D01*
X1616594Y612576D01*
X1617031Y612284D01*
Y611701D01*
X1616594Y611409D01*
G01X1630382Y595076D02*
Y606742D01*
G01Y603826D02*
X1631256Y605284D01*
X1632566Y606451D01*
X1634312Y606742D01*
X1635840Y606451D01*
X1637151Y605284D01*
X1637806Y603243D01*
Y595076D01*
G01X1669094Y612576D02*
Y595076D01*
G01X1666037Y606742D02*
X1672151D01*
G01X1682882Y595076D02*
Y612576D01*
G01Y604118D02*
X1683974Y605576D01*
X1685066Y606451D01*
X1686812Y606742D01*
X1688122Y606451D01*
X1689651Y605284D01*
X1690306Y603534D01*
Y595076D01*
G01X1704094Y606742D02*
Y595076D01*
G01Y611409D02*
X1703657Y611701D01*
Y612284D01*
X1704094Y612576D01*
X1704531Y612284D01*
Y611701D01*
X1704094Y611409D01*
G01X1718319Y597117D02*
X1719411Y595951D01*
X1720939Y595076D01*
X1722249D01*
X1723559Y595659D01*
X1724432Y596534D01*
X1724869Y597700D01*
X1724651Y599451D01*
X1723777Y600326D01*
X1719847Y602076D01*
X1718974Y604118D01*
X1719411Y605576D01*
X1720284Y606451D01*
X1721594Y606742D01*
X1722904Y606451D01*
X1724214Y605576D01*
G01X1756594Y595076D02*
Y612576D01*
G01X1778024Y595076D02*
Y606742D01*
G01Y604701D02*
X1777151Y605867D01*
X1775840Y606451D01*
X1774312Y606742D01*
X1772784Y606159D01*
X1771474Y604993D01*
X1770600Y603243D01*
X1770164Y600909D01*
X1770600Y598576D01*
X1771474Y596826D01*
X1772784Y595659D01*
X1774312Y595076D01*
X1775840Y595368D01*
X1777151Y596242D01*
X1778024Y597409D01*
G01X1787009Y589826D02*
X1788319Y589243D01*
X1790066Y589826D01*
X1791157Y590992D01*
X1792031Y592451D01*
X1793340Y597117D01*
X1796179Y606742D01*
G01X1789192D02*
X1793340Y597117D01*
G01X1805819Y602951D02*
X1812806D01*
X1812151Y604993D01*
X1811059Y606159D01*
X1809531Y606742D01*
X1808002Y606451D01*
X1806692Y605576D01*
X1805819Y603534D01*
X1805382Y601784D01*
Y600034D01*
X1805819Y598284D01*
X1806911Y596534D01*
X1808221Y595368D01*
X1809749Y595076D01*
X1811277Y595659D01*
X1812806Y597409D01*
G01X1823537Y595076D02*
Y606742D01*
G01Y604409D02*
X1824629Y605576D01*
X1825721Y606451D01*
X1827249Y606742D01*
X1828340Y606451D01*
X1829651Y605576D01*
G01X1406594Y572092D02*
Y560426D01*
G01Y576759D02*
X1406157Y577051D01*
Y577634D01*
X1406594Y577926D01*
X1407031Y577634D01*
Y577051D01*
X1406594Y576759D01*
G01X1420382Y560426D02*
Y572092D01*
G01Y569176D02*
X1421256Y570634D01*
X1422566Y571801D01*
X1424312Y572092D01*
X1425840Y571801D01*
X1427151Y570634D01*
X1427806Y568593D01*
Y560426D01*
G01X1438319Y562467D02*
X1439411Y561301D01*
X1440939Y560426D01*
X1442249D01*
X1443559Y561009D01*
X1444432Y561884D01*
X1444869Y563050D01*
X1444651Y564801D01*
X1443777Y565676D01*
X1439847Y567426D01*
X1438974Y569468D01*
X1439411Y570926D01*
X1440284Y571801D01*
X1441594Y572092D01*
X1442904Y571801D01*
X1444214Y570926D01*
G01X1459094Y572092D02*
Y560426D01*
G01Y576759D02*
X1458657Y577051D01*
Y577634D01*
X1459094Y577926D01*
X1459531Y577634D01*
Y577051D01*
X1459094Y576759D01*
G01X1480524Y577926D02*
Y560426D01*
G01Y563050D02*
X1479651Y561592D01*
X1478340Y560718D01*
X1476812Y560426D01*
X1475066Y561009D01*
X1473756Y562467D01*
X1472882Y564217D01*
X1472664Y566259D01*
X1472882Y568301D01*
X1473756Y570051D01*
X1475066Y571509D01*
X1476812Y572092D01*
X1478340Y571801D01*
X1479432Y571217D01*
X1480524Y570051D01*
G01X1490819Y568301D02*
X1497806D01*
X1497151Y570343D01*
X1496059Y571509D01*
X1494531Y572092D01*
X1493002Y571801D01*
X1491692Y570926D01*
X1490819Y568884D01*
X1490382Y567134D01*
Y565384D01*
X1490819Y563634D01*
X1491911Y561884D01*
X1493221Y560718D01*
X1494749Y560426D01*
X1496277Y561009D01*
X1497806Y562759D01*
G01X1525164Y560426D02*
Y577926D01*
G01Y569176D02*
X1526256Y570926D01*
X1527566Y571801D01*
X1528876Y572092D01*
X1530840Y571509D01*
X1532151Y570343D01*
X1533024Y568301D01*
Y565968D01*
X1532587Y563634D01*
X1531714Y561884D01*
X1530186Y560718D01*
X1528876Y560426D01*
X1527566Y560718D01*
X1526256Y561592D01*
X1525164Y563050D01*
G01X1546594Y560426D02*
X1545284Y560718D01*
X1543974Y561884D01*
X1543100Y563926D01*
X1542664Y566259D01*
X1543100Y568593D01*
X1543974Y570634D01*
X1545284Y571801D01*
X1546594Y572092D01*
X1547904Y571801D01*
X1549214Y570634D01*
X1550087Y568593D01*
X1550306Y566259D01*
X1550087Y563926D01*
X1549214Y561884D01*
X1547904Y560718D01*
X1546594Y560426D01*
G01X1568024D02*
Y572092D01*
G01Y570051D02*
X1567151Y571217D01*
X1565840Y571801D01*
X1564312Y572092D01*
X1562784Y571509D01*
X1561474Y570343D01*
X1560600Y568593D01*
X1560164Y566259D01*
X1560600Y563926D01*
X1561474Y562176D01*
X1562784Y561009D01*
X1564312Y560426D01*
X1565840Y560718D01*
X1567151Y561592D01*
X1568024Y562759D01*
G01X1578537Y560426D02*
Y572092D01*
G01Y569759D02*
X1579629Y570926D01*
X1580721Y571801D01*
X1582249Y572092D01*
X1583340Y571801D01*
X1584651Y570926D01*
G01X1603024Y577926D02*
Y560426D01*
G01Y563050D02*
X1602151Y561592D01*
X1600840Y560718D01*
X1599312Y560426D01*
X1597566Y561009D01*
X1596256Y562467D01*
X1595382Y564217D01*
X1595164Y566259D01*
X1595382Y568301D01*
X1596256Y570051D01*
X1597566Y571509D01*
X1599312Y572092D01*
X1600840Y571801D01*
X1601932Y571217D01*
X1603024Y570051D01*
G01X1634094Y560426D02*
X1632784Y560718D01*
X1631474Y561884D01*
X1630600Y563926D01*
X1630164Y566259D01*
X1630600Y568593D01*
X1631474Y570634D01*
X1632784Y571801D01*
X1634094Y572092D01*
X1635404Y571801D01*
X1636714Y570634D01*
X1637587Y568593D01*
X1637806Y566259D01*
X1637587Y563926D01*
X1636714Y561884D01*
X1635404Y560718D01*
X1634094Y560426D01*
G01X1647882Y572092D02*
Y563926D01*
X1648756Y561884D01*
X1650066Y560718D01*
X1651594Y560426D01*
X1653122Y560718D01*
X1654432Y561884D01*
X1655306Y563926D01*
G01Y560426D02*
Y572092D01*
G01X1669094Y577926D02*
Y560426D01*
G01X1666037Y572092D02*
X1672151D01*
G01X1686594Y560426D02*
Y577926D01*
G01X1704094Y572092D02*
Y560426D01*
G01Y576759D02*
X1703657Y577051D01*
Y577634D01*
X1704094Y577926D01*
X1704531Y577634D01*
Y577051D01*
X1704094Y576759D01*
G01X1717882Y560426D02*
Y572092D01*
G01Y569176D02*
X1718756Y570634D01*
X1720066Y571801D01*
X1721812Y572092D01*
X1723340Y571801D01*
X1724651Y570634D01*
X1725306Y568593D01*
Y560426D01*
G01X1735819Y568301D02*
X1742806D01*
X1742151Y570343D01*
X1741059Y571509D01*
X1739531Y572092D01*
X1738002Y571801D01*
X1736692Y570926D01*
X1735819Y568884D01*
X1735382Y567134D01*
Y565384D01*
X1735819Y563634D01*
X1736911Y561884D01*
X1738221Y560718D01*
X1739749Y560426D01*
X1741277Y561009D01*
X1742806Y562759D01*
G01X1756594Y559843D02*
X1756157Y560134D01*
Y560718D01*
X1756594Y561009D01*
X1757031Y560718D01*
Y560134D01*
X1756594Y559843D01*
G01X1331791Y629143D02*
X1341397Y641976D01*
G01X1336594Y644309D02*
Y626809D01*
G01X1341397Y629143D02*
X1331791Y641976D01*
G01X1330044Y635559D02*
X1343144D01*
G01X1368756D02*
X1374432D01*
G01X1401791Y629726D02*
Y647226D01*
X1406157D01*
X1407904Y646351D01*
X1409214Y645184D01*
X1410306Y643435D01*
X1411179Y641392D01*
X1411397Y638476D01*
X1411179Y635559D01*
X1410306Y633517D01*
X1409214Y631767D01*
X1407904Y630601D01*
X1406157Y629726D01*
X1401791D01*
G01X1420819Y637601D02*
X1427806D01*
X1427151Y639643D01*
X1426059Y640809D01*
X1424531Y641392D01*
X1423002Y641101D01*
X1421692Y640226D01*
X1420819Y638184D01*
X1420382Y636434D01*
Y634684D01*
X1420819Y632934D01*
X1421911Y631184D01*
X1423221Y630018D01*
X1424749Y629726D01*
X1426277Y630309D01*
X1427806Y632059D01*
G01X1437882Y629726D02*
Y641392D01*
G01Y638476D02*
X1438756Y639934D01*
X1440066Y641101D01*
X1441812Y641392D01*
X1443340Y641101D01*
X1444651Y639934D01*
X1445306Y637893D01*
Y629726D01*
G01X1459094D02*
X1457784Y630018D01*
X1456474Y631184D01*
X1455600Y633226D01*
X1455164Y635559D01*
X1455600Y637893D01*
X1456474Y639934D01*
X1457784Y641101D01*
X1459094Y641392D01*
X1460404Y641101D01*
X1461714Y639934D01*
X1462587Y637893D01*
X1462806Y635559D01*
X1462587Y633226D01*
X1461714Y631184D01*
X1460404Y630018D01*
X1459094Y629726D01*
G01X1476594Y647226D02*
Y629726D01*
G01X1473537Y641392D02*
X1479651D01*
G01X1490819Y637601D02*
X1497806D01*
X1497151Y639643D01*
X1496059Y640809D01*
X1494531Y641392D01*
X1493002Y641101D01*
X1491692Y640226D01*
X1490819Y638184D01*
X1490382Y636434D01*
Y634684D01*
X1490819Y632934D01*
X1491911Y631184D01*
X1493221Y630018D01*
X1494749Y629726D01*
X1496277Y630309D01*
X1497806Y632059D01*
G01X1508319Y631767D02*
X1509411Y630601D01*
X1510939Y629726D01*
X1512249D01*
X1513559Y630309D01*
X1514432Y631184D01*
X1514869Y632350D01*
X1514651Y634101D01*
X1513777Y634976D01*
X1509847Y636726D01*
X1508974Y638768D01*
X1509411Y640226D01*
X1510284Y641101D01*
X1511594Y641392D01*
X1512904Y641101D01*
X1514214Y640226D01*
G01X1546594Y647226D02*
Y629726D01*
G01X1543537Y641392D02*
X1549651D01*
G01X1560382Y629726D02*
Y647226D01*
G01Y638768D02*
X1561474Y640226D01*
X1562566Y641101D01*
X1564312Y641392D01*
X1565622Y641101D01*
X1567151Y639934D01*
X1567806Y638184D01*
Y629726D01*
G01X1585524D02*
Y641392D01*
G01Y639351D02*
X1584651Y640517D01*
X1583340Y641101D01*
X1581812Y641392D01*
X1580284Y640809D01*
X1578974Y639643D01*
X1578100Y637893D01*
X1577664Y635559D01*
X1578100Y633226D01*
X1578974Y631476D01*
X1580284Y630309D01*
X1581812Y629726D01*
X1583340Y630018D01*
X1584651Y630892D01*
X1585524Y632059D01*
G01X1599094Y647226D02*
Y629726D01*
G01X1596037Y641392D02*
X1602151D01*
G01X1627544Y647226D02*
X1630600Y629726D01*
X1634094Y647226D01*
X1637587Y629726D01*
X1640644Y647226D01*
G01X1648974D02*
X1654214D01*
G01X1651594D02*
Y629726D01*
G01X1648974D02*
X1654214D01*
G01X1664291D02*
Y647226D01*
X1668657D01*
X1670404Y646351D01*
X1671714Y645184D01*
X1672806Y643435D01*
X1673679Y641392D01*
X1673897Y638476D01*
X1673679Y635559D01*
X1672806Y633517D01*
X1671714Y631767D01*
X1670404Y630601D01*
X1668657Y629726D01*
X1664291D01*
G01X1686594Y647226D02*
Y629726D01*
G01X1681572Y647226D02*
X1691616D01*
G01X1699509Y629726D02*
Y647226D01*
G01X1708679D02*
Y629726D01*
G01Y638476D02*
X1699509D01*
G01X0Y-11811D02*
G03X7874Y-19685I7874J0D01*
G01X37008Y0D02*
G03Y-7874I0J-3937D01*
G01X11811D02*
G03Y0I0J3937D01*
G01X0Y-7874D02*
Y-11811D01*
G01X7874Y-19685D02*
X181690D01*
G01X0Y-7874D02*
X11811D01*
G01X25985Y19685D02*
G03X9449I-8268J0D01*
G01D02*
G03X25985I8268J0D01*
G01D02*
G03X9449I-8268J0D01*
G01D02*
G03X25985I8268J0D01*
G01D02*
G03X9449I-8268J0D01*
G01D02*
G03X25985I8268J0D01*
G01D02*
G03X9449I-8268J0D01*
G01D02*
G03X25985I8268J0D01*
G01X9449D02*
G03X25985I8268J0D01*
G01D02*
G03X9449I-8268J0D01*
G01D02*
G03X25985I8268J0D01*
G01D02*
G03X9449I-8268J0D01*
G01X3937Y0D02*
X173229D01*
G01X0Y3937D02*
G03X3937Y0I3937J0D01*
G01X0Y57874D02*
Y3937D01*
G01X37008Y69685D02*
G03Y61811I0J-3937D01*
G01X11811D02*
G03Y69685I0J3937D01*
G01X25985Y89370D02*
G03X9449I-8268J0D01*
G01D02*
G03X25985I8268J0D01*
G01D02*
G03X9449I-8268J0D01*
G01D02*
G03X25985I8268J0D01*
G01D02*
G03X9449I-8268J0D01*
G01D02*
G03X25985I8268J0D01*
G01D02*
G03X9449I-8268J0D01*
G01D02*
G03X25985I8268J0D01*
G01X9449D02*
G03X25985I8268J0D01*
G01D02*
G03X9449I-8268J0D01*
G01D02*
G03X25985I8268J0D01*
G01D02*
G03X9449I-8268J0D01*
G01X3937Y69685D02*
X173229D01*
G01X0Y73622D02*
G03X3937Y69685I3937J0D01*
G01X0Y127559D02*
Y73622D01*
G01X3937Y61811D02*
G03X0Y57874I0J-3937D01*
G01X173229Y61811D02*
X3937D01*
G01X37008Y139370D02*
G03Y131496I0J-3937D01*
G01X11811D02*
G03Y139370I0J3937D01*
G01X25985Y159055D02*
G03X9449I-8268J0D01*
G01D02*
G03X25985I8268J0D01*
G01D02*
G03X9449I-8268J0D01*
G01D02*
G03X25985I8268J0D01*
G01D02*
G03X9449I-8268J0D01*
G01D02*
G03X25985I8268J0D01*
G01D02*
G03X9449I-8268J0D01*
G01D02*
G03X25985I8268J0D01*
G01X9449D02*
G03X25985I8268J0D01*
G01D02*
G03X9449I-8268J0D01*
G01D02*
G03X25985I8268J0D01*
G01D02*
G03X9449I-8268J0D01*
G01X3937Y139370D02*
X173229D01*
G01X0Y143307D02*
G03X3937Y139370I3937J0D01*
G01X0Y197244D02*
Y143307D01*
G01X3937Y131496D02*
G03X0Y127559I0J-3937D01*
G01X173229Y131496D02*
X3937D01*
G01X37008Y278740D02*
G03Y270866I0J-3937D01*
G01X11811D02*
G03Y278740I0J3937D01*
G01X37008Y209055D02*
G03Y201181I0J-3937D01*
G01X11811D02*
G03Y209055I0J3937D01*
G01X3937Y278740D02*
X173229D01*
G01X0Y282677D02*
G03X3937Y278740I3937J0D01*
G01X25985Y228740D02*
G03X9449I-8268J0D01*
G01D02*
G03X25985I8268J0D01*
G01D02*
G03X9449I-8268J0D01*
G01D02*
G03X25985I8268J0D01*
G01D02*
G03X9449I-8268J0D01*
G01D02*
G03X25985I8268J0D01*
G01D02*
G03X9449I-8268J0D01*
G01D02*
G03X25985I8268J0D01*
G01X9449D02*
G03X25985I8268J0D01*
G01D02*
G03X9449I-8268J0D01*
G01D02*
G03X25985I8268J0D01*
G01D02*
G03X9449I-8268J0D01*
G01X3937Y209055D02*
X173229D01*
G01X0Y212992D02*
G03X3937Y209055I3937J0D01*
G01X0Y266929D02*
Y212992D01*
G01X3937Y270866D02*
G03X0Y266929I0J-3937D01*
G01X173229Y270866D02*
X3937D01*
G01Y201181D02*
G03X0Y197244I0J-3937D01*
G01X173229Y201181D02*
X3937D01*
G01X37008Y348425D02*
G03Y340551I0J-3937D01*
G01X11811D02*
G03Y348425I0J3937D01*
G01X9449Y368110D02*
G03X25985I8268J0D01*
G01X9449D02*
G03X25985I8268J0D01*
G01X9449D02*
G03X25985I8268J0D01*
G01X9449D02*
G03X25985I8268J0D01*
G01X9449D02*
G03X25985I8268J0D01*
G01X9449D02*
G03X25985I8268J0D01*
G01X3937Y348425D02*
X173229D01*
G01X0Y352362D02*
G03X3937Y348425I3937J0D01*
G01X0Y406299D02*
Y352362D01*
G01X25985Y298425D02*
G03X9449I-8268J0D01*
G01D02*
G03X25985I8268J0D01*
G01D02*
G03X9449I-8268J0D01*
G01D02*
G03X25985I8268J0D01*
G01D02*
G03X9449I-8268J0D01*
G01D02*
G03X25985I8268J0D01*
G01D02*
G03X9449I-8268J0D01*
G01D02*
G03X25985I8268J0D01*
G01X9449D02*
G03X25985I8268J0D01*
G01D02*
G03X9449I-8268J0D01*
G01D02*
G03X25985I8268J0D01*
G01D02*
G03X9449I-8268J0D01*
G01X0Y336614D02*
Y282677D01*
G01X3937Y340551D02*
G03X0Y336614I0J-3937D01*
G01X173229Y340551D02*
X3937D01*
G01X37008Y418110D02*
G03Y410236I0J-3937D01*
G01X11811D02*
G03Y418110I0J3937D01*
G01X25985Y437795D02*
G03X9449I-8268J0D01*
G01D02*
G03X25985I8268J0D01*
G01D02*
G03X9449I-8268J0D01*
G01D02*
G03X25985I8268J0D01*
G01D02*
G03X9449I-8268J0D01*
G01D02*
G03X25985I8268J0D01*
G01D02*
G03X9449I-8268J0D01*
G01D02*
G03X25985I8268J0D01*
G01X9449D02*
G03X25985I8268J0D01*
G01D02*
G03X9449I-8268J0D01*
G01D02*
G03X25985I8268J0D01*
G01D02*
G03X9449I-8268J0D01*
G01X3937Y418110D02*
X173229D01*
G01X0Y422047D02*
G03X3937Y418110I3937J0D01*
G01X0Y475984D02*
Y422047D01*
G01X25985Y368110D02*
G03X9449I-8268J0D01*
G01X25985D02*
G03X9449I-8268J0D01*
G01X25985D02*
G03X9449I-8268J0D01*
G01X25985D02*
G03X9449I-8268J0D01*
G01X25985D02*
G03X9449I-8268J0D01*
G01X25985D02*
G03X9449I-8268J0D01*
G01X3937Y410236D02*
G03X0Y406299I0J-3937D01*
G01X173229Y410236D02*
X3937D01*
G01X37008Y487795D02*
G03Y479921I0J-3937D01*
G01X11811D02*
G03Y487795I0J3937D01*
G01X25985Y507480D02*
G03X9449I-8268J0D01*
G01D02*
G03X25985I8268J0D01*
G01D02*
G03X9449I-8268J0D01*
G01D02*
G03X25985I8268J0D01*
G01D02*
G03X9449I-8268J0D01*
G01D02*
G03X25985I8268J0D01*
G01D02*
G03X9449I-8268J0D01*
G01D02*
G03X25985I8268J0D01*
G01X9449D02*
G03X25985I8268J0D01*
G01D02*
G03X9449I-8268J0D01*
G01D02*
G03X25985I8268J0D01*
G01D02*
G03X9449I-8268J0D01*
G01X3937Y487795D02*
X173229D01*
G01X0Y491732D02*
G03X3937Y487795I3937J0D01*
G01X0Y545669D02*
Y491732D01*
G01X3937Y479921D02*
G03X0Y475984I0J-3937D01*
G01X173229Y479921D02*
X3937D01*
G01X37008Y557480D02*
G03Y549606I0J-3937D01*
G01X11811D02*
G03Y557480I0J3937D01*
G01X25985Y577165D02*
G03X9449I-8268J0D01*
G01D02*
G03X25985I8268J0D01*
G01D02*
G03X9449I-8268J0D01*
G01D02*
G03X25985I8268J0D01*
G01D02*
G03X9449I-8268J0D01*
G01D02*
G03X25985I8268J0D01*
G01D02*
G03X9449I-8268J0D01*
G01D02*
G03X25985I8268J0D01*
G01X9449D02*
G03X25985I8268J0D01*
G01D02*
G03X9449I-8268J0D01*
G01D02*
G03X25985I8268J0D01*
G01D02*
G03X9449I-8268J0D01*
G01X3937Y557480D02*
X173229D01*
G01X0Y561417D02*
G03X3937Y557480I3937J0D01*
G01X0Y615354D02*
Y561417D01*
G01X3937Y549606D02*
G03X0Y545669I0J-3937D01*
G01X173229Y549606D02*
X3937D01*
G01X37008Y627165D02*
G03Y619291I0J-3937D01*
G01X11811D02*
G03Y627165I0J3937D01*
G01X25985Y646850D02*
G03X9449I-8268J0D01*
G01D02*
G03X25985I8268J0D01*
G01D02*
G03X9449I-8268J0D01*
G01D02*
G03X25985I8268J0D01*
G01D02*
G03X9449I-8268J0D01*
G01D02*
G03X25985I8268J0D01*
G01D02*
G03X9449I-8268J0D01*
G01D02*
G03X25985I8268J0D01*
G01X9449D02*
G03X25985I8268J0D01*
G01D02*
G03X9449I-8268J0D01*
G01D02*
G03X25985I8268J0D01*
G01D02*
G03X9449I-8268J0D01*
G01X3937Y627165D02*
X173229D01*
G01X0Y631102D02*
G03X3937Y627165I3937J0D01*
G01X0Y685039D02*
Y631102D01*
G01X3937Y688976D02*
G03X0Y685039I0J-3937D01*
G01X173229Y688976D02*
X3937D01*
G01Y619291D02*
G03X0Y615354I0J-3937D01*
G01X173229Y619291D02*
X3937D01*
G01X37008Y-7874D02*
X140158D01*
G01X196851D02*
G03Y0I0J3937D01*
G01X189564Y-19685D02*
G03X181690I-3937J0D01*
G01X165355Y0D02*
G03Y-7874I0J-3937D01*
G01X140158D02*
G03Y0I0J3937D01*
G01X185040Y18307D02*
G03X177166I-3937J0D01*
G01X189564Y-19685D02*
X539370D01*
G01X165355Y-7874D02*
X196851D01*
G01X211024Y19685D02*
G03X194489I-8267J0D01*
G01D02*
G03X211024I8267J0D01*
G01D02*
G03X194489I-8267J0D01*
G01D02*
G03X211024I8267J0D01*
G01D02*
G03X194489I-8267J0D01*
G01D02*
G03X211024I8267J0D01*
G01D02*
G03X194489I-8267J0D01*
G01D02*
G03X211024I8267J0D01*
G01X194489D02*
G03X211024I8267J0D01*
G01D02*
G03X194489I-8267J0D01*
G01D02*
G03X211024I8267J0D01*
G01D02*
G03X194489I-8267J0D01*
G01X188977Y0D02*
X358268D01*
G01X185040Y3937D02*
G03X188977Y0I3937J0D01*
G01X185040Y57874D02*
Y3937D01*
G01X167717Y19685D02*
G03X151181I-8268J0D01*
G01D02*
G03X167717I8268J0D01*
G01D02*
G03X151181I-8268J0D01*
G01D02*
G03X167717I8268J0D01*
G01D02*
G03X151181I-8268J0D01*
G01D02*
G03X167717I8268J0D01*
G01D02*
G03X151181I-8268J0D01*
G01D02*
G03X167717I8268J0D01*
G01X151181D02*
G03X167717I8268J0D01*
G01D02*
G03X151181I-8268J0D01*
G01D02*
G03X167717I8268J0D01*
G01D02*
G03X151181I-8268J0D01*
G01X177166Y3937D02*
Y57874D01*
G01X173229Y0D02*
G03X177166Y3937I0J3937D01*
G01X185040Y87992D02*
G03X177166I-3937J0D01*
G01Y113189D02*
G03X185040I3937J0D01*
G01X196851Y61811D02*
G03Y69685I0J3937D01*
G01X165355D02*
G03Y61811I0J-3937D01*
G01X140158D02*
G03Y69685I0J3937D01*
G01X177166Y43504D02*
G03X185040I3937J0D01*
G01X167717Y89370D02*
G03X151181I-8268J0D01*
G01D02*
G03X167717I8268J0D01*
G01D02*
G03X151181I-8268J0D01*
G01D02*
G03X167717I8268J0D01*
G01D02*
G03X151181I-8268J0D01*
G01D02*
G03X167717I8268J0D01*
G01D02*
G03X151181I-8268J0D01*
G01D02*
G03X167717I8268J0D01*
G01X151181D02*
G03X167717I8268J0D01*
G01D02*
G03X151181I-8268J0D01*
G01D02*
G03X167717I8268J0D01*
G01D02*
G03X151181I-8268J0D01*
G01X177166Y73622D02*
Y127559D01*
G01X173229Y69685D02*
G03X177166Y73622I0J3937D01*
G01X211024Y89370D02*
G03X194489I-8267J0D01*
G01D02*
G03X211024I8267J0D01*
G01D02*
G03X194489I-8267J0D01*
G01D02*
G03X211024I8267J0D01*
G01D02*
G03X194489I-8267J0D01*
G01D02*
G03X211024I8267J0D01*
G01D02*
G03X194489I-8267J0D01*
G01D02*
G03X211024I8267J0D01*
G01X194489D02*
G03X211024I8267J0D01*
G01D02*
G03X194489I-8267J0D01*
G01D02*
G03X211024I8267J0D01*
G01D02*
G03X194489I-8267J0D01*
G01X188977Y69685D02*
X358268D01*
G01X185040Y73622D02*
G03X188977Y69685I3937J0D01*
G01X185040Y127559D02*
Y73622D01*
G01X188977Y61811D02*
G03X185040Y57874I0J-3937D01*
G01X358268Y61811D02*
X188977D01*
G01X177166Y57874D02*
G03X173229Y61811I-3937J0D01*
G01X185040Y157677D02*
G03X177166I-3937J0D01*
G01Y182874D02*
G03X185040I3937J0D01*
G01X196851Y131496D02*
G03Y139370I0J3937D01*
G01X165355D02*
G03Y131496I0J-3937D01*
G01X140158D02*
G03Y139370I0J3937D01*
G01X167717Y159055D02*
G03X151181I-8268J0D01*
G01D02*
G03X167717I8268J0D01*
G01D02*
G03X151181I-8268J0D01*
G01D02*
G03X167717I8268J0D01*
G01D02*
G03X151181I-8268J0D01*
G01D02*
G03X167717I8268J0D01*
G01D02*
G03X151181I-8268J0D01*
G01D02*
G03X167717I8268J0D01*
G01X151181D02*
G03X167717I8268J0D01*
G01D02*
G03X151181I-8268J0D01*
G01D02*
G03X167717I8268J0D01*
G01D02*
G03X151181I-8268J0D01*
G01X177166Y143307D02*
Y197244D01*
G01X173229Y139370D02*
G03X177166Y143307I0J3937D01*
G01Y127559D02*
G03X173229Y131496I-3937J0D01*
G01X211024Y159055D02*
G03X194489I-8267J0D01*
G01D02*
G03X211024I8267J0D01*
G01D02*
G03X194489I-8267J0D01*
G01D02*
G03X211024I8267J0D01*
G01D02*
G03X194489I-8267J0D01*
G01D02*
G03X211024I8267J0D01*
G01D02*
G03X194489I-8267J0D01*
G01D02*
G03X211024I8267J0D01*
G01X194489D02*
G03X211024I8267J0D01*
G01D02*
G03X194489I-8267J0D01*
G01D02*
G03X211024I8267J0D01*
G01D02*
G03X194489I-8267J0D01*
G01X188977Y139370D02*
X358268D01*
G01X185040Y143307D02*
G03X188977Y139370I3937J0D01*
G01X185040Y197244D02*
Y143307D01*
G01X188977Y131496D02*
G03X185040Y127559I0J-3937D01*
G01X358268Y131496D02*
X188977D01*
G01X185040Y227362D02*
G03X177166I-3937J0D01*
G01Y252559D02*
G03X185040I3937J0D01*
G01X196851Y270866D02*
G03Y278740I0J3937D01*
G01X165355D02*
G03Y270866I0J-3937D01*
G01X140158D02*
G03Y278740I0J3937D01*
G01X196851Y201181D02*
G03Y209055I0J3937D01*
G01X165355D02*
G03Y201181I0J-3937D01*
G01X140158D02*
G03Y209055I0J3937D01*
G01X173229Y278740D02*
G03X177166Y282677I0J3937D01*
G01X188977Y278740D02*
X358268D01*
G01X185040Y282677D02*
G03X188977Y278740I3937J0D01*
G01X167717Y228740D02*
G03X151181I-8268J0D01*
G01D02*
G03X167717I8268J0D01*
G01D02*
G03X151181I-8268J0D01*
G01D02*
G03X167717I8268J0D01*
G01D02*
G03X151181I-8268J0D01*
G01D02*
G03X167717I8268J0D01*
G01D02*
G03X151181I-8268J0D01*
G01D02*
G03X167717I8268J0D01*
G01X151181D02*
G03X167717I8268J0D01*
G01D02*
G03X151181I-8268J0D01*
G01D02*
G03X167717I8268J0D01*
G01D02*
G03X151181I-8268J0D01*
G01X177166Y212992D02*
Y266929D01*
G01X173229Y209055D02*
G03X177166Y212992I0J3937D01*
G01Y266929D02*
G03X173229Y270866I-3937J0D01*
G01X211024Y228740D02*
G03X194489I-8267J0D01*
G01D02*
G03X211024I8267J0D01*
G01D02*
G03X194489I-8267J0D01*
G01D02*
G03X211024I8267J0D01*
G01D02*
G03X194489I-8267J0D01*
G01D02*
G03X211024I8267J0D01*
G01D02*
G03X194489I-8267J0D01*
G01D02*
G03X211024I8267J0D01*
G01X194489D02*
G03X211024I8267J0D01*
G01D02*
G03X194489I-8267J0D01*
G01D02*
G03X211024I8267J0D01*
G01D02*
G03X194489I-8267J0D01*
G01X188977Y209055D02*
X358268D01*
G01X185040Y212992D02*
G03X188977Y209055I3937J0D01*
G01X185040Y266929D02*
Y212992D01*
G01X188977Y270866D02*
G03X185040Y266929I0J-3937D01*
G01X358268Y270866D02*
X188977D01*
G01X177166Y197244D02*
G03X173229Y201181I-3937J0D01*
G01X188977D02*
G03X185040Y197244I0J-3937D01*
G01X358268Y201181D02*
X188977D01*
G01X185040Y297047D02*
G03X177166I-3937J0D01*
G01Y322244D02*
G03X185040I3937J0D01*
G01X196851Y340551D02*
G03Y348425I0J3937D01*
G01X165355D02*
G03Y340551I0J-3937D01*
G01X140158D02*
G03Y348425I0J3937D01*
G01X151181Y368110D02*
G03X167717I8268J0D01*
G01X151181D02*
G03X167717I8268J0D01*
G01X151181D02*
G03X167717I8268J0D01*
G01X151181D02*
G03X167717I8268J0D01*
G01X151181D02*
G03X167717I8268J0D01*
G01X151181D02*
G03X167717I8268J0D01*
G01X177166Y352362D02*
Y406299D01*
G01X173229Y348425D02*
G03X177166Y352362I0J3937D01*
G01X194489Y368110D02*
G03X211024I8267J0D01*
G01X194489D02*
G03X211024I8267J0D01*
G01X194489D02*
G03X211024I8267J0D01*
G01X194489D02*
G03X211024I8267J0D01*
G01X194489D02*
G03X211024I8267J0D01*
G01X194489D02*
G03X211024I8267J0D01*
G01X188977Y348425D02*
X358268D01*
G01X185040Y352362D02*
G03X188977Y348425I3937J0D01*
G01X185040Y406299D02*
Y352362D01*
G01X167717Y298425D02*
G03X151181I-8268J0D01*
G01D02*
G03X167717I8268J0D01*
G01D02*
G03X151181I-8268J0D01*
G01D02*
G03X167717I8268J0D01*
G01D02*
G03X151181I-8268J0D01*
G01D02*
G03X167717I8268J0D01*
G01D02*
G03X151181I-8268J0D01*
G01D02*
G03X167717I8268J0D01*
G01X151181D02*
G03X167717I8268J0D01*
G01D02*
G03X151181I-8268J0D01*
G01D02*
G03X167717I8268J0D01*
G01D02*
G03X151181I-8268J0D01*
G01X177166Y282677D02*
Y336614D01*
G01D02*
G03X173229Y340551I-3937J0D01*
G01X211024Y298425D02*
G03X194489I-8267J0D01*
G01D02*
G03X211024I8267J0D01*
G01D02*
G03X194489I-8267J0D01*
G01D02*
G03X211024I8267J0D01*
G01D02*
G03X194489I-8267J0D01*
G01D02*
G03X211024I8267J0D01*
G01D02*
G03X194489I-8267J0D01*
G01D02*
G03X211024I8267J0D01*
G01X194489D02*
G03X211024I8267J0D01*
G01D02*
G03X194489I-8267J0D01*
G01D02*
G03X211024I8267J0D01*
G01D02*
G03X194489I-8267J0D01*
G01X185040Y336614D02*
Y282677D01*
G01X188977Y340551D02*
G03X185040Y336614I0J-3937D01*
G01X358268Y340551D02*
X188977D01*
G01X185040Y436417D02*
G03X177166I-3937J0D01*
G01X185040Y366732D02*
G03X177166I-3937J0D01*
G01Y391929D02*
G03X185040I3937J0D01*
G01X196851Y410236D02*
G03Y418110I0J3937D01*
G01X165355D02*
G03Y410236I0J-3937D01*
G01X140158D02*
G03Y418110I0J3937D01*
G01X167717Y437795D02*
G03X151181I-8268J0D01*
G01D02*
G03X167717I8268J0D01*
G01D02*
G03X151181I-8268J0D01*
G01D02*
G03X167717I8268J0D01*
G01D02*
G03X151181I-8268J0D01*
G01D02*
G03X167717I8268J0D01*
G01D02*
G03X151181I-8268J0D01*
G01D02*
G03X167717I8268J0D01*
G01X151181D02*
G03X167717I8268J0D01*
G01D02*
G03X151181I-8268J0D01*
G01D02*
G03X167717I8268J0D01*
G01D02*
G03X151181I-8268J0D01*
G01X177166Y422047D02*
Y475984D01*
G01X173229Y418110D02*
G03X177166Y422047I0J3937D01*
G01X211024Y437795D02*
G03X194489I-8267J0D01*
G01D02*
G03X211024I8267J0D01*
G01D02*
G03X194489I-8267J0D01*
G01D02*
G03X211024I8267J0D01*
G01D02*
G03X194489I-8267J0D01*
G01D02*
G03X211024I8267J0D01*
G01D02*
G03X194489I-8267J0D01*
G01D02*
G03X211024I8267J0D01*
G01X194489D02*
G03X211024I8267J0D01*
G01D02*
G03X194489I-8267J0D01*
G01D02*
G03X211024I8267J0D01*
G01D02*
G03X194489I-8267J0D01*
G01X188977Y418110D02*
X358268D01*
G01X185040Y422047D02*
G03X188977Y418110I3937J0D01*
G01X185040Y475984D02*
Y422047D01*
G01X167717Y368110D02*
G03X151181I-8268J0D01*
G01X167717D02*
G03X151181I-8268J0D01*
G01X167717D02*
G03X151181I-8268J0D01*
G01X167717D02*
G03X151181I-8268J0D01*
G01X167717D02*
G03X151181I-8268J0D01*
G01X167717D02*
G03X151181I-8268J0D01*
G01X177166Y406299D02*
G03X173229Y410236I-3937J0D01*
G01X211024Y368110D02*
G03X194489I-8267J0D01*
G01X211024D02*
G03X194489I-8267J0D01*
G01X211024D02*
G03X194489I-8267J0D01*
G01X211024D02*
G03X194489I-8267J0D01*
G01X211024D02*
G03X194489I-8267J0D01*
G01X211024D02*
G03X194489I-8267J0D01*
G01X188977Y410236D02*
G03X185040Y406299I0J-3937D01*
G01X358268Y410236D02*
X188977D01*
G01X185040Y506102D02*
G03X177166I-3937J0D01*
G01Y531299D02*
G03X185040I3937J0D01*
G01X177166Y461614D02*
G03X185040I3937J0D01*
G01X196851Y479921D02*
G03Y487795I0J3937D01*
G01X165355D02*
G03Y479921I0J-3937D01*
G01X140158D02*
G03Y487795I0J3937D01*
G01X167717Y507480D02*
G03X151181I-8268J0D01*
G01D02*
G03X167717I8268J0D01*
G01D02*
G03X151181I-8268J0D01*
G01D02*
G03X167717I8268J0D01*
G01D02*
G03X151181I-8268J0D01*
G01D02*
G03X167717I8268J0D01*
G01D02*
G03X151181I-8268J0D01*
G01D02*
G03X167717I8268J0D01*
G01X151181D02*
G03X167717I8268J0D01*
G01D02*
G03X151181I-8268J0D01*
G01D02*
G03X167717I8268J0D01*
G01D02*
G03X151181I-8268J0D01*
G01X177166Y491732D02*
Y545669D01*
G01X173229Y487795D02*
G03X177166Y491732I0J3937D01*
G01X211024Y507480D02*
G03X194489I-8267J0D01*
G01D02*
G03X211024I8267J0D01*
G01D02*
G03X194489I-8267J0D01*
G01D02*
G03X211024I8267J0D01*
G01D02*
G03X194489I-8267J0D01*
G01D02*
G03X211024I8267J0D01*
G01D02*
G03X194489I-8267J0D01*
G01D02*
G03X211024I8267J0D01*
G01X194489D02*
G03X211024I8267J0D01*
G01D02*
G03X194489I-8267J0D01*
G01D02*
G03X211024I8267J0D01*
G01D02*
G03X194489I-8267J0D01*
G01X188977Y487795D02*
X358268D01*
G01X185040Y491732D02*
G03X188977Y487795I3937J0D01*
G01X185040Y545669D02*
Y491732D01*
G01X177166Y475984D02*
G03X173229Y479921I-3937J0D01*
G01X188977D02*
G03X185040Y475984I0J-3937D01*
G01X358268Y479921D02*
X188977D01*
G01X185040Y575787D02*
G03X177166I-3937J0D01*
G01Y600984D02*
G03X185040I3937J0D01*
G01X196851Y549606D02*
G03Y557480I0J3937D01*
G01X165355D02*
G03Y549606I0J-3937D01*
G01X140158D02*
G03Y557480I0J3937D01*
G01X167717Y577165D02*
G03X151181I-8268J0D01*
G01D02*
G03X167717I8268J0D01*
G01D02*
G03X151181I-8268J0D01*
G01D02*
G03X167717I8268J0D01*
G01D02*
G03X151181I-8268J0D01*
G01D02*
G03X167717I8268J0D01*
G01D02*
G03X151181I-8268J0D01*
G01D02*
G03X167717I8268J0D01*
G01X151181D02*
G03X167717I8268J0D01*
G01D02*
G03X151181I-8268J0D01*
G01D02*
G03X167717I8268J0D01*
G01D02*
G03X151181I-8268J0D01*
G01X177166Y561417D02*
Y615354D01*
G01X173229Y557480D02*
G03X177166Y561417I0J3937D01*
G01X211024Y577165D02*
G03X194489I-8267J0D01*
G01D02*
G03X211024I8267J0D01*
G01D02*
G03X194489I-8267J0D01*
G01D02*
G03X211024I8267J0D01*
G01D02*
G03X194489I-8267J0D01*
G01D02*
G03X211024I8267J0D01*
G01D02*
G03X194489I-8267J0D01*
G01D02*
G03X211024I8267J0D01*
G01X194489D02*
G03X211024I8267J0D01*
G01D02*
G03X194489I-8267J0D01*
G01D02*
G03X211024I8267J0D01*
G01D02*
G03X194489I-8267J0D01*
G01X188977Y557480D02*
X358268D01*
G01X185040Y561417D02*
G03X188977Y557480I3937J0D01*
G01X185040Y615354D02*
Y561417D01*
G01X177166Y545669D02*
G03X173229Y549606I-3937J0D01*
G01X188977D02*
G03X185040Y545669I0J-3937D01*
G01X358268Y549606D02*
X188977D01*
G01X185040Y645472D02*
G03X177166I-3937J0D01*
G01Y670669D02*
G03X185040I3937J0D01*
G01X196851Y619291D02*
G03Y627165I0J3937D01*
G01X165355D02*
G03Y619291I0J-3937D01*
G01X140158D02*
G03Y627165I0J3937D01*
G01X167717Y646850D02*
G03X151181I-8268J0D01*
G01D02*
G03X167717I8268J0D01*
G01D02*
G03X151181I-8268J0D01*
G01D02*
G03X167717I8268J0D01*
G01D02*
G03X151181I-8268J0D01*
G01D02*
G03X167717I8268J0D01*
G01D02*
G03X151181I-8268J0D01*
G01D02*
G03X167717I8268J0D01*
G01X151181D02*
G03X167717I8268J0D01*
G01D02*
G03X151181I-8268J0D01*
G01D02*
G03X167717I8268J0D01*
G01D02*
G03X151181I-8268J0D01*
G01X177166Y631102D02*
Y685039D01*
G01X173229Y627165D02*
G03X177166Y631102I0J3937D01*
G01Y685039D02*
G03X173229Y688976I-3937J0D01*
G01X211024Y646850D02*
G03X194489I-8267J0D01*
G01D02*
G03X211024I8267J0D01*
G01D02*
G03X194489I-8267J0D01*
G01D02*
G03X211024I8267J0D01*
G01D02*
G03X194489I-8267J0D01*
G01D02*
G03X211024I8267J0D01*
G01D02*
G03X194489I-8267J0D01*
G01D02*
G03X211024I8267J0D01*
G01X194489D02*
G03X211024I8267J0D01*
G01D02*
G03X194489I-8267J0D01*
G01D02*
G03X211024I8267J0D01*
G01D02*
G03X194489I-8267J0D01*
G01X188977Y627165D02*
X358268D01*
G01X185040Y631102D02*
G03X188977Y627165I3937J0D01*
G01X185040Y685039D02*
Y631102D01*
G01X188977Y688976D02*
G03X185040Y685039I0J-3937D01*
G01X358268Y688976D02*
X188977D01*
G01X177166Y615354D02*
G03X173229Y619291I-3937J0D01*
G01X188977D02*
G03X185040Y615354I0J-3937D01*
G01X358268Y619291D02*
X188977D01*
G01X222048Y0D02*
G03Y-7874I0J-3937D01*
G01D02*
X325197D01*
G01X222048Y69685D02*
G03Y61811I0J-3937D01*
G01Y139370D02*
G03Y131496I0J-3937D01*
G01Y278740D02*
G03Y270866I0J-3937D01*
G01Y209055D02*
G03Y201181I0J-3937D01*
G01Y348425D02*
G03Y340551I0J-3937D01*
G01Y418110D02*
G03Y410236I0J-3937D01*
G01Y487795D02*
G03Y479921I0J-3937D01*
G01Y557480D02*
G03Y549606I0J-3937D01*
G01Y627165D02*
G03Y619291I0J-3937D01*
G01X370079Y18307D02*
G03X362205I-3937J0D01*
G01X350394Y0D02*
G03Y-7874I0J-3937D01*
G01X325197D02*
G03Y0I0J3937D01*
G01X350394Y-7874D02*
X381890D01*
G01X352756Y19685D02*
G03X336221I-8267J0D01*
G01D02*
G03X352756I8268J0D01*
G01D02*
G03X336221I-8267J0D01*
G01D02*
G03X352756I8268J0D01*
G01D02*
G03X336221I-8267J0D01*
G01D02*
G03X352756I8268J0D01*
G01D02*
G03X336221I-8267J0D01*
G01D02*
G03X352756I8268J0D01*
G01X336221D02*
G03X352756I8268J0D01*
G01D02*
G03X336221I-8267J0D01*
G01D02*
G03X352756I8268J0D01*
G01D02*
G03X336221I-8267J0D01*
G01X362205Y3937D02*
Y57874D01*
G01X358268Y0D02*
G03X362205Y3937I0J3937D01*
G01X370079Y87992D02*
G03X362205I-3937J0D01*
G01Y113189D02*
G03X370079I3937J0D01*
G01X362205Y43504D02*
G03X370079I3937J0D01*
G01X350394Y69685D02*
G03Y61811I0J-3937D01*
G01X325197D02*
G03Y69685I0J3937D01*
G01X352756Y89370D02*
G03X336221I-8267J0D01*
G01D02*
G03X352756I8268J0D01*
G01D02*
G03X336221I-8267J0D01*
G01D02*
G03X352756I8268J0D01*
G01D02*
G03X336221I-8267J0D01*
G01D02*
G03X352756I8268J0D01*
G01D02*
G03X336221I-8267J0D01*
G01D02*
G03X352756I8268J0D01*
G01X336221D02*
G03X352756I8268J0D01*
G01D02*
G03X336221I-8267J0D01*
G01D02*
G03X352756I8268J0D01*
G01D02*
G03X336221I-8267J0D01*
G01X362205Y73622D02*
Y127559D01*
G01X358268Y69685D02*
G03X362205Y73622I0J3937D01*
G01Y57874D02*
G03X358268Y61811I-3937J0D01*
G01X370079Y157677D02*
G03X362205I-3937J0D01*
G01Y182874D02*
G03X370079I3937J0D01*
G01X350394Y139370D02*
G03Y131496I0J-3937D01*
G01X325197D02*
G03Y139370I0J3937D01*
G01X352756Y159055D02*
G03X336221I-8267J0D01*
G01D02*
G03X352756I8268J0D01*
G01D02*
G03X336221I-8267J0D01*
G01D02*
G03X352756I8268J0D01*
G01D02*
G03X336221I-8267J0D01*
G01D02*
G03X352756I8268J0D01*
G01D02*
G03X336221I-8267J0D01*
G01D02*
G03X352756I8268J0D01*
G01X336221D02*
G03X352756I8268J0D01*
G01D02*
G03X336221I-8267J0D01*
G01D02*
G03X352756I8268J0D01*
G01D02*
G03X336221I-8267J0D01*
G01X362205Y143307D02*
Y197244D01*
G01X358268Y139370D02*
G03X362205Y143307I0J3937D01*
G01Y127559D02*
G03X358268Y131496I-3937J0D01*
G01X370079Y227362D02*
G03X362205I-3937J0D01*
G01Y252559D02*
G03X370079I3937J0D01*
G01X350394Y278740D02*
G03Y270866I0J-3937D01*
G01X325197D02*
G03Y278740I0J3937D01*
G01X350394Y209055D02*
G03Y201181I0J-3937D01*
G01X325197D02*
G03Y209055I0J3937D01*
G01X358268Y278740D02*
G03X362205Y282677I0J3937D01*
G01X352756Y228740D02*
G03X336221I-8267J0D01*
G01D02*
G03X352756I8268J0D01*
G01D02*
G03X336221I-8267J0D01*
G01D02*
G03X352756I8268J0D01*
G01D02*
G03X336221I-8267J0D01*
G01D02*
G03X352756I8268J0D01*
G01D02*
G03X336221I-8267J0D01*
G01D02*
G03X352756I8268J0D01*
G01X336221D02*
G03X352756I8268J0D01*
G01D02*
G03X336221I-8267J0D01*
G01D02*
G03X352756I8268J0D01*
G01D02*
G03X336221I-8267J0D01*
G01X362205Y212992D02*
Y266929D01*
G01X358268Y209055D02*
G03X362205Y212992I0J3937D01*
G01Y266929D02*
G03X358268Y270866I-3937J0D01*
G01X362205Y197244D02*
G03X358268Y201181I-3937J0D01*
G01X370079Y297047D02*
G03X362205I-3937J0D01*
G01Y322244D02*
G03X370079I3937J0D01*
G01X350394Y348425D02*
G03Y340551I0J-3937D01*
G01X325197D02*
G03Y348425I0J3937D01*
G01X336221Y368110D02*
G03X352756I8268J0D01*
G01X336221D02*
G03X352756I8268J0D01*
G01X336221D02*
G03X352756I8268J0D01*
G01X336221D02*
G03X352756I8268J0D01*
G01X336221D02*
G03X352756I8268J0D01*
G01X336221D02*
G03X352756I8268J0D01*
G01X362205Y352362D02*
Y406299D01*
G01X358268Y348425D02*
G03X362205Y352362I0J3937D01*
G01X352756Y298425D02*
G03X336221I-8267J0D01*
G01D02*
G03X352756I8268J0D01*
G01D02*
G03X336221I-8267J0D01*
G01D02*
G03X352756I8268J0D01*
G01D02*
G03X336221I-8267J0D01*
G01D02*
G03X352756I8268J0D01*
G01D02*
G03X336221I-8267J0D01*
G01D02*
G03X352756I8268J0D01*
G01X336221D02*
G03X352756I8268J0D01*
G01D02*
G03X336221I-8267J0D01*
G01D02*
G03X352756I8268J0D01*
G01D02*
G03X336221I-8267J0D01*
G01X362205Y282677D02*
Y336614D01*
G01D02*
G03X358268Y340551I-3937J0D01*
G01X370079Y436417D02*
G03X362205I-3937J0D01*
G01X370079Y366732D02*
G03X362205I-3937J0D01*
G01Y391929D02*
G03X370079I3937J0D01*
G01X350394Y418110D02*
G03Y410236I0J-3937D01*
G01X325197D02*
G03Y418110I0J3937D01*
G01X352756Y437795D02*
G03X336221I-8267J0D01*
G01D02*
G03X352756I8268J0D01*
G01D02*
G03X336221I-8267J0D01*
G01D02*
G03X352756I8268J0D01*
G01D02*
G03X336221I-8267J0D01*
G01D02*
G03X352756I8268J0D01*
G01D02*
G03X336221I-8267J0D01*
G01D02*
G03X352756I8268J0D01*
G01X336221D02*
G03X352756I8268J0D01*
G01D02*
G03X336221I-8267J0D01*
G01D02*
G03X352756I8268J0D01*
G01D02*
G03X336221I-8267J0D01*
G01X362205Y422047D02*
Y475984D01*
G01X358268Y418110D02*
G03X362205Y422047I0J3937D01*
G01X352756Y368110D02*
G03X336221I-8267J0D01*
G01X352756D02*
G03X336221I-8267J0D01*
G01X352756D02*
G03X336221I-8267J0D01*
G01X352756D02*
G03X336221I-8267J0D01*
G01X352756D02*
G03X336221I-8267J0D01*
G01X352756D02*
G03X336221I-8267J0D01*
G01X362205Y406299D02*
G03X358268Y410236I-3937J0D01*
G01X370079Y506102D02*
G03X362205I-3937J0D01*
G01Y531299D02*
G03X370079I3937J0D01*
G01X362205Y461614D02*
G03X370079I3937J0D01*
G01X350394Y487795D02*
G03Y479921I0J-3937D01*
G01X325197D02*
G03Y487795I0J3937D01*
G01X352756Y507480D02*
G03X336221I-8267J0D01*
G01D02*
G03X352756I8268J0D01*
G01D02*
G03X336221I-8267J0D01*
G01D02*
G03X352756I8268J0D01*
G01D02*
G03X336221I-8267J0D01*
G01D02*
G03X352756I8268J0D01*
G01D02*
G03X336221I-8267J0D01*
G01D02*
G03X352756I8268J0D01*
G01X336221D02*
G03X352756I8268J0D01*
G01D02*
G03X336221I-8267J0D01*
G01D02*
G03X352756I8268J0D01*
G01D02*
G03X336221I-8267J0D01*
G01X362205Y491732D02*
Y545669D01*
G01X358268Y487795D02*
G03X362205Y491732I0J3937D01*
G01Y475984D02*
G03X358268Y479921I-3937J0D01*
G01X370079Y575787D02*
G03X362205I-3937J0D01*
G01Y600984D02*
G03X370079I3937J0D01*
G01X350394Y557480D02*
G03Y549606I0J-3937D01*
G01X325197D02*
G03Y557480I0J3937D01*
G01X352756Y577165D02*
G03X336221I-8267J0D01*
G01D02*
G03X352756I8268J0D01*
G01D02*
G03X336221I-8267J0D01*
G01D02*
G03X352756I8268J0D01*
G01D02*
G03X336221I-8267J0D01*
G01D02*
G03X352756I8268J0D01*
G01D02*
G03X336221I-8267J0D01*
G01D02*
G03X352756I8268J0D01*
G01X336221D02*
G03X352756I8268J0D01*
G01D02*
G03X336221I-8267J0D01*
G01D02*
G03X352756I8268J0D01*
G01D02*
G03X336221I-8267J0D01*
G01X362205Y561417D02*
Y615354D01*
G01X358268Y557480D02*
G03X362205Y561417I0J3937D01*
G01Y545669D02*
G03X358268Y549606I-3937J0D01*
G01X370079Y645472D02*
G03X362205I-3937J0D01*
G01Y670669D02*
G03X370079I3937J0D01*
G01X350394Y627165D02*
G03Y619291I0J-3937D01*
G01X325197D02*
G03Y627165I0J3937D01*
G01X352756Y646850D02*
G03X336221I-8267J0D01*
G01D02*
G03X352756I8268J0D01*
G01D02*
G03X336221I-8267J0D01*
G01D02*
G03X352756I8268J0D01*
G01D02*
G03X336221I-8267J0D01*
G01D02*
G03X352756I8268J0D01*
G01D02*
G03X336221I-8267J0D01*
G01D02*
G03X352756I8268J0D01*
G01X336221D02*
G03X352756I8268J0D01*
G01D02*
G03X336221I-8267J0D01*
G01D02*
G03X352756I8268J0D01*
G01D02*
G03X336221I-8267J0D01*
G01X362205Y631102D02*
Y685039D01*
G01X358268Y627165D02*
G03X362205Y631102I0J3937D01*
G01Y685039D02*
G03X358268Y688976I-3937J0D01*
G01X362205Y615354D02*
G03X358268Y619291I-3937J0D01*
G01X407087Y0D02*
G03Y-7874I0J-3937D01*
G01X381890D02*
G03Y0I0J3937D01*
G01X407087Y-7874D02*
X510237D01*
G01X396063Y19685D02*
G03X379528I-8268J0D01*
G01D02*
G03X396063I8267J0D01*
G01D02*
G03X379528I-8268J0D01*
G01D02*
G03X396063I8267J0D01*
G01D02*
G03X379528I-8268J0D01*
G01D02*
G03X396063I8267J0D01*
G01D02*
G03X379528I-8268J0D01*
G01D02*
G03X396063I8267J0D01*
G01X379528D02*
G03X396063I8267J0D01*
G01D02*
G03X379528I-8268J0D01*
G01D02*
G03X396063I8267J0D01*
G01D02*
G03X379528I-8268J0D01*
G01X374016Y0D02*
X543307D01*
G01X370079Y3937D02*
G03X374016Y0I3937J0D01*
G01X370079Y57874D02*
Y3937D01*
G01X407087Y69685D02*
G03Y61811I0J-3937D01*
G01X381890D02*
G03Y69685I0J3937D01*
G01X396063Y89370D02*
G03X379528I-8268J0D01*
G01D02*
G03X396063I8267J0D01*
G01D02*
G03X379528I-8268J0D01*
G01D02*
G03X396063I8267J0D01*
G01D02*
G03X379528I-8268J0D01*
G01D02*
G03X396063I8267J0D01*
G01D02*
G03X379528I-8268J0D01*
G01D02*
G03X396063I8267J0D01*
G01X379528D02*
G03X396063I8267J0D01*
G01D02*
G03X379528I-8268J0D01*
G01D02*
G03X396063I8267J0D01*
G01D02*
G03X379528I-8268J0D01*
G01X374016Y69685D02*
X543307D01*
G01X370079Y73622D02*
G03X374016Y69685I3937J0D01*
G01X370079Y127559D02*
Y73622D01*
G01X374016Y61811D02*
G03X370079Y57874I0J-3937D01*
G01X543307Y61811D02*
X374016D01*
G01X407087Y139370D02*
G03Y131496I0J-3937D01*
G01X381890D02*
G03Y139370I0J3937D01*
G01X396063Y159055D02*
G03X379528I-8268J0D01*
G01D02*
G03X396063I8267J0D01*
G01D02*
G03X379528I-8268J0D01*
G01D02*
G03X396063I8267J0D01*
G01D02*
G03X379528I-8268J0D01*
G01D02*
G03X396063I8267J0D01*
G01D02*
G03X379528I-8268J0D01*
G01D02*
G03X396063I8267J0D01*
G01X379528D02*
G03X396063I8267J0D01*
G01D02*
G03X379528I-8268J0D01*
G01D02*
G03X396063I8267J0D01*
G01D02*
G03X379528I-8268J0D01*
G01X374016Y139370D02*
X543307D01*
G01X370079Y143307D02*
G03X374016Y139370I3937J0D01*
G01X370079Y197244D02*
Y143307D01*
G01X374016Y131496D02*
G03X370079Y127559I0J-3937D01*
G01X543307Y131496D02*
X374016D01*
G01X407087Y278740D02*
G03Y270866I0J-3937D01*
G01X381890D02*
G03Y278740I0J3937D01*
G01X407087Y209055D02*
G03Y201181I0J-3937D01*
G01X381890D02*
G03Y209055I0J3937D01*
G01X374016Y278740D02*
X543307D01*
G01X370079Y282677D02*
G03X374016Y278740I3937J0D01*
G01X396063Y228740D02*
G03X379528I-8268J0D01*
G01D02*
G03X396063I8267J0D01*
G01D02*
G03X379528I-8268J0D01*
G01D02*
G03X396063I8267J0D01*
G01D02*
G03X379528I-8268J0D01*
G01D02*
G03X396063I8267J0D01*
G01D02*
G03X379528I-8268J0D01*
G01D02*
G03X396063I8267J0D01*
G01X379528D02*
G03X396063I8267J0D01*
G01D02*
G03X379528I-8268J0D01*
G01D02*
G03X396063I8267J0D01*
G01D02*
G03X379528I-8268J0D01*
G01X374016Y209055D02*
X543307D01*
G01X370079Y212992D02*
G03X374016Y209055I3937J0D01*
G01X370079Y266929D02*
Y212992D01*
G01X374016Y270866D02*
G03X370079Y266929I0J-3937D01*
G01X543307Y270866D02*
X374016D01*
G01Y201181D02*
G03X370079Y197244I0J-3937D01*
G01X543307Y201181D02*
X374016D01*
G01X407087Y348425D02*
G03Y340551I0J-3937D01*
G01X381890D02*
G03Y348425I0J3937D01*
G01X379528Y368110D02*
G03X396063I8267J0D01*
G01X379528D02*
G03X396063I8267J0D01*
G01X379528D02*
G03X396063I8267J0D01*
G01X379528D02*
G03X396063I8267J0D01*
G01X379528D02*
G03X396063I8267J0D01*
G01X379528D02*
G03X396063I8267J0D01*
G01X374016Y348425D02*
X543307D01*
G01X370079Y352362D02*
G03X374016Y348425I3937J0D01*
G01X370079Y406299D02*
Y352362D01*
G01X396063Y298425D02*
G03X379528I-8268J0D01*
G01D02*
G03X396063I8267J0D01*
G01D02*
G03X379528I-8268J0D01*
G01D02*
G03X396063I8267J0D01*
G01D02*
G03X379528I-8268J0D01*
G01D02*
G03X396063I8267J0D01*
G01D02*
G03X379528I-8268J0D01*
G01D02*
G03X396063I8267J0D01*
G01X379528D02*
G03X396063I8267J0D01*
G01D02*
G03X379528I-8268J0D01*
G01D02*
G03X396063I8267J0D01*
G01D02*
G03X379528I-8268J0D01*
G01X370079Y336614D02*
Y282677D01*
G01X374016Y340551D02*
G03X370079Y336614I0J-3937D01*
G01X543307Y340551D02*
X374016D01*
G01X407087Y418110D02*
G03Y410236I0J-3937D01*
G01X381890D02*
G03Y418110I0J3937D01*
G01X396063Y437795D02*
G03X379528I-8268J0D01*
G01D02*
G03X396063I8267J0D01*
G01D02*
G03X379528I-8268J0D01*
G01D02*
G03X396063I8267J0D01*
G01D02*
G03X379528I-8268J0D01*
G01D02*
G03X396063I8267J0D01*
G01D02*
G03X379528I-8268J0D01*
G01D02*
G03X396063I8267J0D01*
G01X379528D02*
G03X396063I8267J0D01*
G01D02*
G03X379528I-8268J0D01*
G01D02*
G03X396063I8267J0D01*
G01D02*
G03X379528I-8268J0D01*
G01X374016Y418110D02*
X543307D01*
G01X370079Y422047D02*
G03X374016Y418110I3937J0D01*
G01X370079Y475984D02*
Y422047D01*
G01X396063Y368110D02*
G03X379528I-8268J0D01*
G01X396063D02*
G03X379528I-8268J0D01*
G01X396063D02*
G03X379528I-8268J0D01*
G01X396063D02*
G03X379528I-8268J0D01*
G01X396063D02*
G03X379528I-8268J0D01*
G01X396063D02*
G03X379528I-8268J0D01*
G01X374016Y410236D02*
G03X370079Y406299I0J-3937D01*
G01X543307Y410236D02*
X374016D01*
G01X407087Y487795D02*
G03Y479921I0J-3937D01*
G01X381890D02*
G03Y487795I0J3937D01*
G01X396063Y507480D02*
G03X379528I-8268J0D01*
G01D02*
G03X396063I8267J0D01*
G01D02*
G03X379528I-8268J0D01*
G01D02*
G03X396063I8267J0D01*
G01D02*
G03X379528I-8268J0D01*
G01D02*
G03X396063I8267J0D01*
G01D02*
G03X379528I-8268J0D01*
G01D02*
G03X396063I8267J0D01*
G01X379528D02*
G03X396063I8267J0D01*
G01D02*
G03X379528I-8268J0D01*
G01D02*
G03X396063I8267J0D01*
G01D02*
G03X379528I-8268J0D01*
G01X374016Y487795D02*
X543307D01*
G01X370079Y491732D02*
G03X374016Y487795I3937J0D01*
G01X370079Y545669D02*
Y491732D01*
G01X374016Y479921D02*
G03X370079Y475984I0J-3937D01*
G01X543307Y479921D02*
X374016D01*
G01X407087Y557480D02*
G03Y549606I0J-3937D01*
G01X381890D02*
G03Y557480I0J3937D01*
G01X396063Y577165D02*
G03X379528I-8268J0D01*
G01D02*
G03X396063I8267J0D01*
G01D02*
G03X379528I-8268J0D01*
G01D02*
G03X396063I8267J0D01*
G01D02*
G03X379528I-8268J0D01*
G01D02*
G03X396063I8267J0D01*
G01D02*
G03X379528I-8268J0D01*
G01D02*
G03X396063I8267J0D01*
G01X379528D02*
G03X396063I8267J0D01*
G01D02*
G03X379528I-8268J0D01*
G01D02*
G03X396063I8267J0D01*
G01D02*
G03X379528I-8268J0D01*
G01X374016Y557480D02*
X543307D01*
G01X370079Y561417D02*
G03X374016Y557480I3937J0D01*
G01X370079Y615354D02*
Y561417D01*
G01X374016Y549606D02*
G03X370079Y545669I0J-3937D01*
G01X543307Y549606D02*
X374016D01*
G01X407087Y627165D02*
G03Y619291I0J-3937D01*
G01X381890D02*
G03Y627165I0J3937D01*
G01X396063Y646850D02*
G03X379528I-8268J0D01*
G01D02*
G03X396063I8267J0D01*
G01D02*
G03X379528I-8268J0D01*
G01D02*
G03X396063I8267J0D01*
G01D02*
G03X379528I-8268J0D01*
G01D02*
G03X396063I8267J0D01*
G01D02*
G03X379528I-8268J0D01*
G01D02*
G03X396063I8267J0D01*
G01X379528D02*
G03X396063I8267J0D01*
G01D02*
G03X379528I-8268J0D01*
G01D02*
G03X396063I8267J0D01*
G01D02*
G03X379528I-8268J0D01*
G01X374016Y627165D02*
X543307D01*
G01X370079Y631102D02*
G03X374016Y627165I3937J0D01*
G01X370079Y685039D02*
Y631102D01*
G01X374016Y688976D02*
G03X370079Y685039I0J-3937D01*
G01X543307Y688976D02*
X374016D01*
G01Y619291D02*
G03X370079Y615354I0J-3937D01*
G01X543307Y619291D02*
X374016D01*
G01X510237Y-7874D02*
G03Y0I0J3937D01*
G01X537796Y19685D02*
G03X521260I-8268J0D01*
G01D02*
G03X537796I8268J0D01*
G01D02*
G03X521260I-8268J0D01*
G01D02*
G03X537796I8268J0D01*
G01D02*
G03X521260I-8268J0D01*
G01D02*
G03X537796I8268J0D01*
G01D02*
G03X521260I-8268J0D01*
G01D02*
G03X537796I8268J0D01*
G01X521260D02*
G03X537796I8268J0D01*
G01D02*
G03X521260I-8268J0D01*
G01D02*
G03X537796I8268J0D01*
G01D02*
G03X521260I-8268J0D01*
G01X510237Y61811D02*
G03Y69685I0J3937D01*
G01X537796Y89370D02*
G03X521260I-8268J0D01*
G01D02*
G03X537796I8268J0D01*
G01D02*
G03X521260I-8268J0D01*
G01D02*
G03X537796I8268J0D01*
G01D02*
G03X521260I-8268J0D01*
G01D02*
G03X537796I8268J0D01*
G01D02*
G03X521260I-8268J0D01*
G01D02*
G03X537796I8268J0D01*
G01X521260D02*
G03X537796I8268J0D01*
G01D02*
G03X521260I-8268J0D01*
G01D02*
G03X537796I8268J0D01*
G01D02*
G03X521260I-8268J0D01*
G01X510237Y131496D02*
G03Y139370I0J3937D01*
G01X537796Y159055D02*
G03X521260I-8268J0D01*
G01D02*
G03X537796I8268J0D01*
G01D02*
G03X521260I-8268J0D01*
G01D02*
G03X537796I8268J0D01*
G01D02*
G03X521260I-8268J0D01*
G01D02*
G03X537796I8268J0D01*
G01D02*
G03X521260I-8268J0D01*
G01D02*
G03X537796I8268J0D01*
G01X521260D02*
G03X537796I8268J0D01*
G01D02*
G03X521260I-8268J0D01*
G01D02*
G03X537796I8268J0D01*
G01D02*
G03X521260I-8268J0D01*
G01X510237Y270866D02*
G03Y278740I0J3937D01*
G01Y201181D02*
G03Y209055I0J3937D01*
G01X537796Y228740D02*
G03X521260I-8268J0D01*
G01D02*
G03X537796I8268J0D01*
G01D02*
G03X521260I-8268J0D01*
G01D02*
G03X537796I8268J0D01*
G01D02*
G03X521260I-8268J0D01*
G01D02*
G03X537796I8268J0D01*
G01D02*
G03X521260I-8268J0D01*
G01D02*
G03X537796I8268J0D01*
G01X521260D02*
G03X537796I8268J0D01*
G01D02*
G03X521260I-8268J0D01*
G01D02*
G03X537796I8268J0D01*
G01D02*
G03X521260I-8268J0D01*
G01X510237Y340551D02*
G03Y348425I0J3937D01*
G01X521260Y368110D02*
G03X537796I8268J0D01*
G01X521260D02*
G03X537796I8268J0D01*
G01X521260D02*
G03X537796I8268J0D01*
G01X521260D02*
G03X537796I8268J0D01*
G01X521260D02*
G03X537796I8268J0D01*
G01X521260D02*
G03X537796I8268J0D01*
G01Y298425D02*
G03X521260I-8268J0D01*
G01D02*
G03X537796I8268J0D01*
G01D02*
G03X521260I-8268J0D01*
G01D02*
G03X537796I8268J0D01*
G01D02*
G03X521260I-8268J0D01*
G01D02*
G03X537796I8268J0D01*
G01D02*
G03X521260I-8268J0D01*
G01D02*
G03X537796I8268J0D01*
G01X521260D02*
G03X537796I8268J0D01*
G01D02*
G03X521260I-8268J0D01*
G01D02*
G03X537796I8268J0D01*
G01D02*
G03X521260I-8268J0D01*
G01X510237Y410236D02*
G03Y418110I0J3937D01*
G01X537796Y437795D02*
G03X521260I-8268J0D01*
G01D02*
G03X537796I8268J0D01*
G01D02*
G03X521260I-8268J0D01*
G01D02*
G03X537796I8268J0D01*
G01D02*
G03X521260I-8268J0D01*
G01D02*
G03X537796I8268J0D01*
G01D02*
G03X521260I-8268J0D01*
G01D02*
G03X537796I8268J0D01*
G01X521260D02*
G03X537796I8268J0D01*
G01D02*
G03X521260I-8268J0D01*
G01D02*
G03X537796I8268J0D01*
G01D02*
G03X521260I-8268J0D01*
G01X537796Y368110D02*
G03X521260I-8268J0D01*
G01X537796D02*
G03X521260I-8268J0D01*
G01X537796D02*
G03X521260I-8268J0D01*
G01X537796D02*
G03X521260I-8268J0D01*
G01X537796D02*
G03X521260I-8268J0D01*
G01X537796D02*
G03X521260I-8268J0D01*
G01X510237Y479921D02*
G03Y487795I0J3937D01*
G01X537796Y507480D02*
G03X521260I-8268J0D01*
G01D02*
G03X537796I8268J0D01*
G01D02*
G03X521260I-8268J0D01*
G01D02*
G03X537796I8268J0D01*
G01D02*
G03X521260I-8268J0D01*
G01D02*
G03X537796I8268J0D01*
G01D02*
G03X521260I-8268J0D01*
G01D02*
G03X537796I8268J0D01*
G01X521260D02*
G03X537796I8268J0D01*
G01D02*
G03X521260I-8268J0D01*
G01D02*
G03X537796I8268J0D01*
G01D02*
G03X521260I-8268J0D01*
G01X510237Y549606D02*
G03Y557480I0J3937D01*
G01X537796Y577165D02*
G03X521260I-8268J0D01*
G01D02*
G03X537796I8268J0D01*
G01D02*
G03X521260I-8268J0D01*
G01D02*
G03X537796I8268J0D01*
G01D02*
G03X521260I-8268J0D01*
G01D02*
G03X537796I8268J0D01*
G01D02*
G03X521260I-8268J0D01*
G01D02*
G03X537796I8268J0D01*
G01X521260D02*
G03X537796I8268J0D01*
G01D02*
G03X521260I-8268J0D01*
G01D02*
G03X537796I8268J0D01*
G01D02*
G03X521260I-8268J0D01*
G01X510237Y619291D02*
G03Y627165I0J3937D01*
G01X537796Y646850D02*
G03X521260I-8268J0D01*
G01D02*
G03X537796I8268J0D01*
G01D02*
G03X521260I-8268J0D01*
G01D02*
G03X537796I8268J0D01*
G01D02*
G03X521260I-8268J0D01*
G01D02*
G03X537796I8268J0D01*
G01D02*
G03X521260I-8268J0D01*
G01D02*
G03X537796I8268J0D01*
G01X521260D02*
G03X537796I8268J0D01*
G01D02*
G03X521260I-8268J0D01*
G01D02*
G03X537796I8268J0D01*
G01D02*
G03X521260I-8268J0D01*
G01X539370Y-19685D02*
G03X547244Y-11811I0J7874D01*
G01X535433Y0D02*
G03Y-7874I0J-3937D01*
G01X547244D02*
Y-11811D01*
G01X535433Y-7874D02*
X547244D01*
G01Y3937D02*
Y57874D01*
G01X543307Y0D02*
G03X547244Y3937I0J3937D01*
G01X535433Y69685D02*
G03Y61811I0J-3937D01*
G01X547244Y73622D02*
Y127559D01*
G01X543307Y69685D02*
G03X547244Y73622I0J3937D01*
G01Y57874D02*
G03X543307Y61811I-3937J0D01*
G01X535433Y139370D02*
G03Y131496I0J-3937D01*
G01X547244Y143307D02*
Y197244D01*
G01X543307Y139370D02*
G03X547244Y143307I0J3937D01*
G01Y127559D02*
G03X543307Y131496I-3937J0D01*
G01X535433Y278740D02*
G03Y270866I0J-3937D01*
G01Y209055D02*
G03Y201181I0J-3937D01*
G01X543307Y278740D02*
G03X547244Y282677I0J3937D01*
G01Y212992D02*
Y266929D01*
G01X543307Y209055D02*
G03X547244Y212992I0J3937D01*
G01Y266929D02*
G03X543307Y270866I-3937J0D01*
G01X547244Y197244D02*
G03X543307Y201181I-3937J0D01*
G01X535433Y348425D02*
G03Y340551I0J-3937D01*
G01X547244Y352362D02*
Y406299D01*
G01X543307Y348425D02*
G03X547244Y352362I0J3937D01*
G01Y282677D02*
Y336614D01*
G01D02*
G03X543307Y340551I-3937J0D01*
G01X535433Y418110D02*
G03Y410236I0J-3937D01*
G01X547244Y422047D02*
Y475984D01*
G01X543307Y418110D02*
G03X547244Y422047I0J3937D01*
G01Y406299D02*
G03X543307Y410236I-3937J0D01*
G01X535433Y487795D02*
G03Y479921I0J-3937D01*
G01X547244Y491732D02*
Y545669D01*
G01X543307Y487795D02*
G03X547244Y491732I0J3937D01*
G01Y475984D02*
G03X543307Y479921I-3937J0D01*
G01X535433Y557480D02*
G03Y549606I0J-3937D01*
G01X547244Y561417D02*
Y615354D01*
G01X543307Y557480D02*
G03X547244Y561417I0J3937D01*
G01Y545669D02*
G03X543307Y549606I-3937J0D01*
G01X535433Y627165D02*
G03Y619291I0J-3937D01*
G01X547244Y631102D02*
Y685039D01*
G01X543307Y627165D02*
G03X547244Y631102I0J3937D01*
G01Y685039D02*
G03X543307Y688976I-3937J0D01*
G01X547244Y615354D02*
G03X543307Y619291I-3937J0D01*
M02*
